G04 ================== begin FILE IDENTIFICATION RECORD ==================*
G04 Layout Name:  DA0T6MTH8C0_t6m_tray_bp_c_brd_103112_274.brd*
G04 Film Name:    vcc1*
G04 File Format:  Gerber RS274X*
G04 File Origin:  Cadence Allegro 16.3-S048*
G04 Origin Date:  Tue Nov 26 11:26:41 2013*
G04 *
G04 Layer:  DRAWING FORMAT/TITLE_BLOCK*
G04 Layer:  VIA CLASS/VCC1*
G04 Layer:  PIN/VCC1*
G04 Layer:  MANUFACTURING/PHOTOPLOT_OUTLINE*
G04 Layer:  ETCH/VCC1*
G04 Layer:  DRAWING FORMAT/TITLE_DATA_VCC1*
G04 *
G04 Offset:    (0.00 0.00)*
G04 Mirror:    No*
G04 Mode:      Negative*
G04 Rotation:  0*
G04 FullContactRelief:  No*
G04 UndefLineWidth:     6.00*
G04 ================== end FILE IDENTIFICATION RECORD ====================*
%FSLAX25Y25*MOIN*%
%IR0*IPPOS*OFA0.00000B0.00000*MIA0B0*SFA1.00000B1.00000*%
%ADD21C,.03*%
%ADD22C,.04*%
%ADD24C,.05*%
%ADD10C,.042*%
%ADD29C,.061*%
%ADD31C,.053*%
%ADD19C,.072*%
%ADD16C,.063*%
%ADD36C,.082*%
%ADD32C,.055*%
%ADD14C,.073*%
%ADD28C,.093*%
%ADD27C,.057*%
%ADD11C,.066*%
%ADD20C,.058*%
%AMMACRO17*
4,1,36,0.0,.009,
.001563,.008863,
.003078,.008457,
.0045,.007794,
.005785,.006894,
.006894,.005785,
.007794,.0045,
.008457,.003078,
.008863,.001563,
.009,0.0,
.008863,-.001563,
.008457,-.003078,
.007794,-.0045,
.006894,-.005785,
.005785,-.006894,
.0045,-.007794,
.003078,-.008457,
.001563,-.008863,
0.0,-.009,
-.001563,-.008863,
-.003078,-.008457,
-.0045,-.007794,
-.005785,-.006894,
-.006894,-.005785,
-.007794,-.0045,
-.008457,-.003078,
-.008863,-.001563,
-.009,0.0,
-.008863,.001563,
-.008457,.003078,
-.007794,.0045,
-.006894,.005785,
-.005785,.006894,
-.0045,.007794,
-.003078,.008457,
-.001563,.008863,
0.0,.009,
0.0*
%
%ADD17MACRO17*%
%AMMACRO26*
4,1,36,0.0,.014,
-.002431,.013787,
-.004788,.013156,
-.007,.012124,
-.008999,.010725,
-.010725,.008999,
-.012124,.007,
-.013156,.004788,
-.013787,.002431,
-.014,0.0,
-.013787,-.002431,
-.013156,-.004788,
-.012124,-.007,
-.010725,-.008999,
-.008999,-.010725,
-.007,-.012124,
-.004788,-.013156,
-.002431,-.013787,
0.0,-.014,
.002431,-.013787,
.004788,-.013156,
.007,-.012124,
.008999,-.010725,
.010725,-.008999,
.012124,-.007,
.013156,-.004788,
.013787,-.002431,
.014,0.0,
.013787,.002431,
.013156,.004788,
.012124,.007,
.010725,.008999,
.008999,.010725,
.007,.012124,
.004788,.013156,
.002431,.013787,
0.0,.014,
0.0*
%
%ADD26MACRO26*%
%AMMACRO15*
4,1,16,.02548,.01487,
.027675,.01022,
.029029,.005259,
.029501,.000138,
.029077,-.004987,
.027769,-.009961,
.025618,-.014631,
.02548,-.01487,
.03056,-.01996,
.033562,-.01435,
.035544,-.008304,
.036446,-.002006,
.03624,.004353,
.034934,.01058,
.032566,.016486,
.03056,.01996,
.02548,.01487,
90.*
4,1,16,.01487,-.02548,
.01022,-.027675,
.005259,-.029029,
.000138,-.029501,
-.004987,-.029077,
-.009961,-.027769,
-.014631,-.025618,
-.01487,-.02548,
-.01996,-.03056,
-.01435,-.033562,
-.008304,-.035544,
-.002006,-.036446,
.004353,-.03624,
.01058,-.034934,
.016486,-.032566,
.01996,-.03056,
.01487,-.02548,
90.*
4,1,16,-.02548,-.01487,
-.027675,-.01022,
-.029029,-.005259,
-.029501,-.000138,
-.029077,.004987,
-.027769,.009961,
-.025618,.014631,
-.02548,.01487,
-.03056,.01996,
-.033562,.01435,
-.035544,.008304,
-.036446,.002006,
-.03624,-.004353,
-.034934,-.01058,
-.032566,-.016486,
-.03056,-.01996,
-.02548,-.01487,
90.*
4,1,16,-.01487,.02548,
-.01022,.027675,
-.005259,.029029,
-.000138,.029501,
.004987,.029077,
.009961,.027769,
.014631,.025618,
.01487,.02548,
.01996,.03056,
.01435,.033562,
.008304,.035544,
.002006,.036446,
-.004353,.03624,
-.01058,.034934,
-.016486,.032566,
-.01996,.03056,
-.01487,.02548,
90.*
%
%ADD15MACRO15*%
%ADD33C,.1*%
%ADD25C,.115*%
%ADD12C,.172*%
%ADD35C,.119*%
%ADD34C,.158*%
%ADD30O,.068X.093*%
%ADD13C,.168*%
%ADD23C,.178*%
%AMMACRO18*
4,1,36,0.0,.004,
.000695,.003939,
.001368,.003759,
.002,.003464,
.002571,.003064,
.003064,.002571,
.003464,.002,
.003759,.001368,
.003939,.000695,
.004,0.0,
.003939,-.000695,
.003759,-.001368,
.003464,-.002,
.003064,-.002571,
.002571,-.003064,
.002,-.003464,
.001368,-.003759,
.000695,-.003939,
0.0,-.004,
-.000695,-.003939,
-.001368,-.003759,
-.002,-.003464,
-.002571,-.003064,
-.003064,-.002571,
-.003464,-.002,
-.003759,-.001368,
-.003939,-.000695,
-.004,0.0,
-.003939,.000695,
-.003759,.001368,
-.003464,.002,
-.003064,.002571,
-.002571,.003064,
-.002,.003464,
-.001368,.003759,
-.000695,.003939,
0.0,.004,
0.0*
%
%ADD18MACRO18*%
%ADD37C,.006*%
%ADD40R,.057X.111*%
%ADD39R,.051X.109*%
%ADD38R,.051X.11294*%
%ADD42C,.09612*%
%ADD48C,.07608*%
%ADD43C,.09606*%
%ADD44C,.1601*%
%ADD45C,.16024*%
%ADD46C,.11706*%
%ADD41R,.072X.096*%
%ADD47C,.11708*%
G75*
%LPD*%
G75*
G36*
G01X-471400Y-391900D02*
X2244200D01*
Y1528800D01*
X-471400D01*
Y-391900D01*
G37*
%LPC*%
G75*
G36*
G01X28200Y4000D02*
G02X27700Y4500I0J500D01*
G01Y5453D01*
X27799Y5657D01*
X27889Y5729D01*
G03X5355Y29173I-10172J12774D01*
G01X5283Y29090D01*
X5087Y29000D01*
X4500D01*
G02X4000Y29500I0J500D01*
G01Y126800D01*
G02X5757Y127454I1000J0D01*
G03X6606Y126546I11964J10336D01*
G01X6676Y126476D01*
X6827Y126119D01*
Y114367D01*
G03Y113977I10889J-195D01*
G01Y113334D01*
X6858Y113303D01*
X6876Y113124D01*
Y113123D01*
G03X28606Y114173I10840J1050D01*
G01Y126119D01*
X28757Y126476D01*
X28827Y126546D01*
G03X5756Y148135I-11111J11249D01*
G02X4000Y148789I-756J654D01*
G01Y182700D01*
G02X4500Y183200I500J0D01*
G01X36642D01*
G02X37142Y182700I0J-500D01*
G01Y167916D01*
G03X47898I5378J0D01*
G01Y177600D01*
G02X48398Y178100I500J0D01*
G01X200539D01*
G02X201039Y177600I0J-500D01*
G01Y170551D01*
G03X208976Y162614I7937J0D01*
G01X216850D01*
G03X224787Y170551I0J7937D01*
G01Y198110D01*
G02X228661Y201984I3874J0D01*
G01X304870D01*
G02X305426Y200153I0J-1000D01*
G03X303102Y175760I8786J-13144D01*
G01X303172Y175690D01*
X303323Y175333D01*
Y163581D01*
G03Y163191I10889J-195D01*
G01Y162548D01*
X303354Y162517D01*
X303372Y162338D01*
Y162337D01*
G03X325102Y163387I10840J1050D01*
G01Y175333D01*
X325253Y175690D01*
X325323Y175760D01*
G03X322999Y200153I-11110J11249D01*
G02X323555Y201984I556J831D01*
G01X372200D01*
G02X372700Y201484I0J-500D01*
G01Y200000D01*
G03X380637Y192063I7937J0D01*
G01X441220D01*
G03X449157Y200000I0J7937D01*
G01Y201484D01*
G02X449657Y201984I500J0D01*
G01X523020D01*
G02X523520Y201484I0J-500D01*
G01Y200000D01*
G03X531457Y192063I7937J0D01*
G01X590512D01*
G03X598449Y200000I0J7937D01*
G01Y201484D01*
G02X598949Y201984I500J0D01*
G01X625418D01*
G02X625907Y201586I0J-500D01*
G01X625945Y201404D01*
X626475Y199134D01*
X627301Y197924D01*
X627473Y197089D01*
X628199Y196610D01*
X628690Y195892D01*
X629527Y195734D01*
X630783Y194906D01*
X633430Y194386D01*
X797954D01*
X798318Y194142D01*
X799562Y194386D01*
X800830D01*
X801140Y194696D01*
X802209Y194906D01*
X803465Y195734D01*
X804302Y195892D01*
X804793Y196610D01*
X805519Y197089D01*
X805691Y197924D01*
X806517Y199134D01*
X807047Y201404D01*
X807085Y201586D01*
G02X807574Y201984I489J-102D01*
G01X816683D01*
G02X817238Y200153I-1J-1000D01*
G03X814913Y175759I8785J-13145D01*
G01X814983Y175689D01*
X815134Y175332D01*
Y163580D01*
G03Y163190I10889J-195D01*
G01Y162547D01*
X815165Y162516D01*
X815183Y162337D01*
Y162336D01*
G03X836913Y163386I10840J1050D01*
G01Y175332D01*
X837064Y175689D01*
X837134Y175759D01*
G03X834809Y200153I-11110J11249D01*
G02X835365Y201984I556J831D01*
G01X1174951D01*
G02X1175506Y200153I-1J-1000D01*
G03X1173181Y175759I8785J-13145D01*
G01X1173251Y175689D01*
X1173402Y175332D01*
Y163580D01*
G03Y163190I10889J-195D01*
G01Y162547D01*
X1173433Y162516D01*
X1173451Y162337D01*
Y162336D01*
G03X1195181Y163386I10840J1050D01*
G01Y175332D01*
X1195332Y175689D01*
X1195402Y175759D01*
G03X1193077Y200153I-11110J11249D01*
G02X1193633Y201984I556J831D01*
G01X1243807D01*
G02X1244307Y201484I0J-500D01*
G01Y200000D01*
G03X1252244Y192063I7937J0D01*
G01X1311299D01*
G03X1319236Y200000I0J7937D01*
G01Y201484D01*
G02X1319736Y201984I500J0D01*
G01X1393098D01*
G02X1393598Y201484I0J-500D01*
G01Y200000D01*
G03X1401535Y192063I7937J0D01*
G01X1460590D01*
G03X1468527Y200000I0J7937D01*
G01Y201484D01*
G02X1469027Y201984I500J0D01*
G01X1495497D01*
G02X1495986Y201586I0J-500D01*
G01X1496024Y201404D01*
X1496554Y199134D01*
X1498769Y195892D01*
X1499606Y195734D01*
X1500862Y194906D01*
X1503509Y194386D01*
X1675630D01*
G02X1679504Y190512I0J-3874D01*
G01Y173678D01*
G03X1679517Y173218I7937J-6D01*
G01X1679518Y173204D01*
Y167935D01*
X1679080Y167497D01*
X1678911D01*
X1678800Y167386D01*
X1671611D01*
X1669268Y165043D01*
Y120016D01*
X1678900D01*
G02X1679400Y119516I0J-500D01*
G01Y40700D01*
X1682700Y37400D01*
X1683728D01*
G02X1684228Y36900I0J-500D01*
G01Y29500D01*
G02X1683728Y29000I-500J0D01*
G01X1682975D01*
X1682778Y29090D01*
X1682707Y29171D01*
G03X1668439Y34572I-12194J-10667D01*
G03X1660606Y5684I2073J-16068D01*
G01X1660698Y5613D01*
X1660800Y5405D01*
Y4500D01*
G02X1660300Y4000I-500J0D01*
G01X1529075D01*
G02X1528607Y4325I0J500D01*
G03X1528503Y4547I-1408J-524D01*
G01X1528437Y4663D01*
Y4796D01*
G02X1528937Y5296I500J0D01*
G01X1529653D01*
Y16590D01*
X1524553D01*
Y5296D01*
X1525463D01*
G02X1525963Y4796I0J-500D01*
G01Y4663D01*
X1525897Y4547D01*
G03X1525793Y4325I1304J-746D01*
G02X1525325Y4000I-468J175D01*
G01X476246D01*
X475982Y4194D01*
X475933Y4350D01*
G03X473067I-1433J-450D01*
G02X472590Y4000I-477J150D01*
G01X28200D01*
G37*
%LPD*%
G75*
G36*
G01X754466Y123562D02*
X754389Y123624D01*
X754296Y123652D01*
X753860Y124088D01*
Y125372D01*
X754768Y126280D01*
X761052D01*
X761960Y125372D01*
Y124088D01*
X761052Y123180D01*
X754768D01*
X754767Y123181D01*
Y123210D01*
X754654Y123427D01*
X754552Y123497D01*
G02X754466Y123562I862J1230D01*
G37*
G36*
G01X1624544D02*
X1624467Y123624D01*
X1624374Y123652D01*
X1623938Y124088D01*
Y125372D01*
X1624846Y126280D01*
X1631130D01*
X1632038Y125372D01*
Y124088D01*
X1631130Y123180D01*
X1624846D01*
X1624845Y123181D01*
Y123210D01*
X1624732Y123427D01*
X1624630Y123497D01*
G02X1624544Y123562I862J1230D01*
G37*
G36*
G01X430493Y61456D02*
G02X434096Y57853I0J-3603D01*
G01Y55353D01*
G02X427090I-3503J0D01*
G01Y58053D01*
G02X430493Y61456I3403J0D01*
G37*
G36*
G01X579785D02*
G02X583388Y57854I1J-3602D01*
G01Y55354D01*
G02X576382I-3503J0D01*
G01Y58054D01*
G02X579784Y61456I3402J0D01*
G01X579785D01*
G37*
G36*
G01X1300572D02*
G02X1304174Y57854I0J-3602D01*
G01Y55354D01*
G02X1297169I-3503J0D01*
G01X1297170Y58054D01*
G02X1300572Y61456I3402J0D01*
G37*
G36*
G01X1449864Y61455D02*
G02X1453466Y57853I0J-3602D01*
G01Y55353D01*
G02X1446462I-3502J0D01*
G01Y58053D01*
G02X1449864Y61455I3402J0D01*
G37*
G36*
G01X1391400Y14800D02*
Y21500D01*
X1392500Y22600D01*
X1394200D01*
X1395400Y21400D01*
Y14700D01*
X1394200Y13500D01*
X1392700D01*
X1391400Y14800D01*
G37*
G36*
G01X1436800Y21700D02*
Y23300D01*
X1438000Y24500D01*
X1444700D01*
X1445800Y23400D01*
Y21700D01*
X1444500Y20400D01*
X1438100D01*
X1436800Y21700D01*
G37*
G36*
G01X1268600Y21200D02*
Y22800D01*
X1269800Y24000D01*
X1276400D01*
X1277600Y22800D01*
Y21000D01*
X1276500Y19900D01*
X1269900D01*
X1268600Y21200D01*
G37*
G36*
G01X1315900Y35400D02*
Y37000D01*
X1317100Y38200D01*
X1324400D01*
X1325600Y37000D01*
Y35400D01*
X1324400Y34200D01*
X1317100D01*
X1315900Y35400D01*
G37*
G36*
G01X445900Y35300D02*
Y37000D01*
X447100Y38200D01*
X454400D01*
X455500Y37100D01*
Y35400D01*
X454200Y34100D01*
X447100D01*
X445900Y35300D01*
G37*
G36*
G01X566700Y21700D02*
Y23300D01*
X567900Y24500D01*
X574600D01*
X575700Y23400D01*
Y21600D01*
X574500Y20400D01*
X568000D01*
X566700Y21700D01*
G37*
G36*
G01X521300Y14800D02*
Y21400D01*
X522500Y22600D01*
X524100D01*
X525300Y21400D01*
Y14700D01*
X524100Y13500D01*
X522600D01*
X521300Y14800D01*
G37*
G36*
G01X764161Y121880D02*
X770445D01*
X771353Y120972D01*
Y119653D01*
X770480Y118780D01*
X764161D01*
X763253Y119688D01*
Y120972D01*
X764161Y121880D01*
G37*
G36*
G01X1550048Y131150D02*
X1556332D01*
X1557240Y130242D01*
Y128958D01*
X1556332Y128050D01*
X1550048D01*
X1549140Y128958D01*
Y130242D01*
X1550048Y131150D01*
G37*
G36*
G01X679970D02*
X686254D01*
X687162Y130242D01*
Y128958D01*
X686254Y128050D01*
X679970D01*
X679062Y128958D01*
Y130242D01*
X679970Y131150D01*
G37*
G36*
G01X1540499Y127480D02*
X1546783D01*
X1547691Y126572D01*
Y125288D01*
X1546783Y124380D01*
X1540499D01*
X1539591Y125288D01*
Y126572D01*
X1540499Y127480D01*
G37*
G36*
G01X670421D02*
X676705D01*
X677613Y126572D01*
Y125288D01*
X676705Y124380D01*
X670421D01*
X669513Y125288D01*
Y126572D01*
X670421Y127480D01*
G37*
G36*
G01X1559397Y123580D02*
X1565681D01*
X1566589Y122672D01*
Y121388D01*
X1565681Y120480D01*
X1559397D01*
X1558489Y121388D01*
Y122672D01*
X1559397Y123580D01*
G37*
G36*
G01X689319D02*
X695603D01*
X696511Y122672D01*
Y121388D01*
X695603Y120480D01*
X689319D01*
X688411Y121388D01*
Y122672D01*
X689319Y123580D01*
G37*
G36*
G01X1531050Y122550D02*
X1537334D01*
X1538242Y121642D01*
Y120358D01*
X1537334Y119450D01*
X1531050D01*
X1530142Y120358D01*
Y121642D01*
X1531050Y122550D01*
G37*
G36*
G01X660972D02*
X667256D01*
X668164Y121642D01*
Y120358D01*
X667256Y119450D01*
X660972D01*
X660064Y120358D01*
Y121642D01*
X660972Y122550D01*
G37*
G36*
G01X1615341Y122002D02*
X1621625D01*
X1622533Y121094D01*
Y119810D01*
X1621625Y118902D01*
X1615341D01*
X1614433Y119810D01*
Y121094D01*
X1615341Y122002D01*
G37*
G36*
G01X745263D02*
X751547D01*
X752455Y121094D01*
Y119810D01*
X751547Y118902D01*
X745263D01*
X744355Y119810D01*
Y121094D01*
X745263Y122002D01*
G37*
G36*
G01X1634239Y121880D02*
X1640523D01*
X1641431Y120972D01*
Y119688D01*
X1640523Y118780D01*
X1634239D01*
X1633331Y119688D01*
Y120972D01*
X1634239Y121880D01*
G37*
G36*
G01X1594746Y116940D02*
X1601030D01*
X1601938Y116032D01*
Y114748D01*
X1601030Y113840D01*
X1594746D01*
X1593838Y114748D01*
Y116032D01*
X1594746Y116940D01*
G37*
G36*
G01X724668D02*
X730952D01*
X731860Y116032D01*
Y114748D01*
X730952Y113840D01*
X724668D01*
X723760Y114748D01*
Y116032D01*
X724668Y116940D01*
G37*
G36*
G01X1593836Y107150D02*
X1600120D01*
X1601028Y106242D01*
Y104958D01*
X1600120Y104050D01*
X1593836D01*
X1592928Y104958D01*
Y106242D01*
X1593836Y107150D01*
G37*
G36*
G01X723758D02*
X730042D01*
X730950Y106242D01*
Y104958D01*
X730042Y104050D01*
X723758D01*
X722850Y104958D01*
Y106242D01*
X723758Y107150D01*
G37*
G36*
G01X1542074Y94840D02*
X1548358D01*
X1549266Y93932D01*
Y92648D01*
X1548358Y91740D01*
X1542074D01*
X1541166Y92648D01*
Y93932D01*
X1542074Y94840D01*
G37*
G36*
G01X671996D02*
X678280D01*
X679188Y93932D01*
Y92648D01*
X678280Y91740D01*
X671996D01*
X671088Y92648D01*
Y93932D01*
X671996Y94840D01*
G37*
G36*
G01X1616916Y94380D02*
X1623200D01*
X1624108Y93472D01*
Y92188D01*
X1623200Y91280D01*
X1616916D01*
X1616008Y92188D01*
Y93472D01*
X1616916Y94380D01*
G37*
G36*
G01X746838D02*
X753122D01*
X754030Y93472D01*
Y92188D01*
X753122Y91280D01*
X746838D01*
X745930Y92188D01*
Y93472D01*
X746838Y94380D01*
G37*
G36*
G01X1647636Y98680D02*
X1648920D01*
X1649828Y97772D01*
Y91488D01*
X1648920Y90580D01*
X1647636D01*
X1646728Y91488D01*
Y97772D01*
X1647636Y98680D01*
G37*
G36*
G01X777558D02*
X778842D01*
X779750Y97772D01*
Y91488D01*
X778842Y90580D01*
X777558D01*
X776650Y91488D01*
Y97772D01*
X777558Y98680D01*
G37*
G36*
G01X1571106Y98650D02*
X1572390D01*
X1573298Y97742D01*
Y91458D01*
X1572390Y90550D01*
X1571106D01*
X1570198Y91458D01*
Y97742D01*
X1571106Y98650D01*
G37*
G36*
G01X1523836D02*
X1525120D01*
X1526028Y97742D01*
Y91458D01*
X1525120Y90550D01*
X1523836D01*
X1522928Y91458D01*
Y97742D01*
X1523836Y98650D01*
G37*
G36*
G01X701028D02*
X702312D01*
X703220Y97742D01*
Y91458D01*
X702312Y90550D01*
X701028D01*
X700120Y91458D01*
Y97742D01*
X701028Y98650D01*
G37*
G36*
G01X653758D02*
X655042D01*
X655950Y97742D01*
Y91458D01*
X655042Y90550D01*
X653758D01*
X652850Y91458D01*
Y97742D01*
X653758Y98650D01*
G37*
G36*
G01X1626365Y74450D02*
X1632649D01*
X1633557Y73542D01*
Y72258D01*
X1632649Y71350D01*
X1626365D01*
X1625457Y72258D01*
Y73542D01*
X1626365Y74450D01*
G37*
G36*
G01X1528746D02*
X1535030D01*
X1535938Y73542D01*
Y72258D01*
X1535030Y71350D01*
X1528746D01*
X1527838Y72258D01*
Y73542D01*
X1528746Y74450D01*
G37*
G36*
G01X756287D02*
X762571D01*
X763479Y73542D01*
Y72258D01*
X762571Y71350D01*
X756287D01*
X755379Y72258D01*
Y73542D01*
X756287Y74450D01*
G37*
G36*
G01X658668D02*
X664952D01*
X665860Y73542D01*
Y72258D01*
X664952Y71350D01*
X658668D01*
X657760Y72258D01*
Y73542D01*
X658668Y74450D01*
G37*
G36*
G01X399703Y23960D02*
X406359D01*
X407531Y22788D01*
Y21132D01*
X406359Y19960D01*
X399703D01*
X398531Y21132D01*
Y22788D01*
X399703Y23960D01*
G37*
G36*
G01X772772Y18702D02*
Y30450D01*
G03X772621Y30808I-500J0D01*
G02X794702I11041J11318D01*
G03X794551Y30450I349J-358D01*
G01Y18504D01*
G02X772821Y17455I-10890J0D01*
G01X772803Y17634D01*
X772772Y17665D01*
Y18304D01*
G02Y18702I10889J199D01*
G37*
G36*
G01X1090725Y18701D02*
Y30449D01*
G03X1090574Y30807I-500J0D01*
G02X1112655I11041J11318D01*
G03X1112504Y30449I349J-358D01*
G01Y18503D01*
G02X1090774Y17454I-10890J0D01*
G01X1090756Y17633D01*
X1090725Y17664D01*
Y18303D01*
G02Y18701I10889J199D01*
G37*
G36*
G01X83188Y71770D02*
X82328D01*
G02X82327Y73896I3538J1065D01*
G01X83185D01*
G03X83617Y74144I0J500D01*
G02X84604Y75110I2248J-1310D01*
G03X84862Y75548I-242J438D01*
G01Y76390D01*
G02X86870I1004J-3555D01*
G01Y75548D01*
G03X87128Y75110I500J0D01*
G02X88119Y74136I-1262J-2275D01*
G03X88552Y73886I433J250D01*
G01X89408D01*
G02X89560Y72835I-3542J-1049D01*
G02X89404Y71770I-3694J-3D01*
G01X88544D01*
G03X88112Y71522I0J-500D01*
G02X87126Y70559I-2246J1313D01*
G03X86868Y70121I242J-438D01*
G01Y69279D01*
G02X84864I-1002J3556D01*
G01Y70121D01*
G03X84606Y70559I-500J0D01*
G02X83620Y71522I1260J2276D01*
G03X83188Y71770I-432J-252D01*
G37*
G36*
G01Y103266D02*
X82328D01*
G02X82327Y105392I3538J1065D01*
G01X83185D01*
G03X83617Y105640I0J500D01*
G02X84604Y106606I2248J-1310D01*
G03X84862Y107044I-242J438D01*
G01Y107886D01*
G02X86870I1004J-3555D01*
G01Y107044D01*
G03X87128Y106606I500J0D01*
G02X88119Y105632I-1262J-2275D01*
G03X88552Y105382I433J250D01*
G01X89408D01*
G02X89560Y104331I-3542J-1049D01*
G02X89404Y103266I-3694J-3D01*
G01X88544D01*
G03X88112Y103018I0J-500D01*
G02X87126Y102055I-2246J1313D01*
G03X86868Y101617I242J-438D01*
G01Y100775D01*
G02X84864I-1002J3556D01*
G01Y101617D01*
G03X84606Y102055I-500J0D01*
G02X83620Y103018I1260J2276D01*
G03X83188Y103266I-432J-252D01*
G37*
G54D40*
X506020Y27497D03*
X1376099D03*
X466650Y32615D03*
X1336729D03*
X506020Y44032D03*
X1376099D03*
X466650Y49150D03*
X1336729D03*
G54D39*
X649150Y16078D03*
X680646D03*
X1519229D03*
X1550725D03*
X649150Y32614D03*
X664898D03*
X680646D03*
X1519229D03*
X1534977D03*
X1550725D03*
X649150Y49150D03*
X664898D03*
X680646D03*
X1519229D03*
X1534977D03*
X1550725D03*
G54D38*
X657024Y10943D03*
X688520D03*
X1558599D03*
X657024Y27479D03*
X672772D03*
X688520D03*
X1527103D03*
X1542851D03*
X1558599D03*
X657024Y44015D03*
X672772D03*
X688520D03*
X1527103D03*
X1542851D03*
X1558599D03*
G54D42*
X1647618Y132244D03*
X1572775D03*
X777539D03*
X702697D03*
G54D48*
X40827Y147638D03*
Y29528D03*
G54D43*
X1600374Y132244D03*
X1525531D03*
X1412164Y56653D03*
X1262872Y56654D03*
X730295Y132244D03*
X655453D03*
X542085Y56654D03*
X392793Y56653D03*
G54D44*
X1378938Y176650D03*
X508859D03*
G54D45*
X1333938D03*
X463859D03*
G54D46*
X1221732Y37400D03*
G54D41*
X403008Y40499D03*
X421906D03*
X1422379D03*
X1441277D03*
X552300Y40500D03*
X571198D03*
X1273087D03*
X1291985D03*
G54D47*
X351654Y37401D03*
G54D21*
X99100Y127470D03*
X120500Y59400D03*
X114400Y59700D03*
X107500Y59500D03*
X102400Y59600D03*
X111958Y73600D03*
X121958Y70900D03*
X116958Y68600D03*
X106958Y68500D03*
X102590Y115680D03*
X115400Y120270D03*
X107390Y125110D03*
X119800Y124390D03*
X108900Y137300D03*
X114300Y134900D03*
X119700Y132400D03*
X111500Y129900D03*
X128600Y114510D03*
X132500Y110100D03*
X125000Y126400D03*
X141400Y164800D03*
X129000D03*
X169200Y165200D03*
X155500Y164800D03*
X183300Y164700D03*
X346800Y113500D03*
X345400Y107600D03*
X346200Y102500D03*
X350700Y121642D03*
X345900Y125100D03*
X347350Y143750D03*
X346906Y137693D03*
X362500Y97100D03*
X357600Y97000D03*
X357800Y114657D03*
X357600Y108561D03*
X356861Y102961D03*
X367200Y124000D03*
X397800Y23600D03*
Y19500D03*
X398307Y35000D03*
Y46100D03*
X396732Y78932D03*
X417900Y6700D03*
X414900Y6500D03*
X410200Y6700D03*
X404400Y6800D03*
X408200Y23500D03*
Y19900D03*
X405531Y21960D03*
X400531D03*
X400100Y13900D03*
X412800Y16200D03*
X417205Y35000D03*
X407600D03*
X407756Y46100D03*
X417205D03*
X410906D03*
X414055Y46200D03*
X412480Y80900D03*
X403032Y89532D03*
X415630Y80700D03*
X412300Y85600D03*
X421929Y78400D03*
X409331Y88600D03*
X406181Y82300D03*
X399882Y79318D03*
X426500Y35000D03*
X426654Y46100D03*
X426200Y78100D03*
X446000Y38400D03*
Y33900D03*
X455400Y34000D03*
Y38600D03*
X447880Y36200D03*
X453480D03*
X465600Y55900D03*
X463435Y79865D03*
X453900Y92300D03*
X466200Y87558D03*
X453300Y86800D03*
X451100Y81400D03*
X452100Y97000D03*
X466100Y83258D03*
X452000Y102200D03*
X466300Y100900D03*
X474500Y3900D03*
X490200Y4000D03*
X488800Y73700D03*
X488000Y89800D03*
X477630Y88900D03*
X488800Y93800D03*
X507200Y4200D03*
X505700Y90200D03*
X511600Y108000D03*
X520900Y22500D03*
X525600Y22600D03*
Y13900D03*
X520800Y13800D03*
X523300Y15580D03*
Y20580D03*
X525700Y99300D03*
X519400Y96400D03*
X520439Y91000D03*
X516500Y87442D03*
X559425Y13575D03*
X560198Y46100D03*
X556900Y35000D03*
X547599D03*
X557048Y46100D03*
X547599D03*
X558623Y79200D03*
X552324Y78500D03*
X546024Y79200D03*
X549174Y89400D03*
X575600Y7600D03*
X571500Y7500D03*
X567500Y7300D03*
X563100Y7200D03*
X582416Y16466D03*
X567100Y20500D03*
X575900Y20800D03*
X575800Y24300D03*
X567000Y24400D03*
X573721Y22500D03*
X568721D03*
X563347Y46100D03*
X575946D03*
X566497D03*
X575800Y35000D03*
X566497D03*
X571221Y79700D03*
X568072Y81500D03*
X564922Y81900D03*
X561772Y80800D03*
X574371Y78400D03*
X563800Y87700D03*
X604400Y96000D03*
X604200Y107400D03*
X614900Y90157D03*
X615600Y95139D03*
X626100Y99900D03*
X625600Y95400D03*
X625700Y90100D03*
X615500Y100157D03*
X622658Y112158D03*
X622200Y120258D03*
X626600Y106100D03*
X615500Y105157D03*
X626173Y148400D03*
X617949Y147000D03*
X648300Y55600D03*
X651500Y94700D03*
X651100Y91100D03*
X655200Y4100D03*
X661600Y75900D03*
X667200Y75700D03*
X665100Y55900D03*
X659310Y72900D03*
X664310D03*
X654400Y92100D03*
Y97100D03*
X670414Y96486D03*
X672638Y93290D03*
X666614Y121000D03*
X661614D03*
X658400Y102500D03*
X659390Y117490D03*
X668839Y117661D03*
X671063Y125930D03*
X676063D03*
X667500Y126200D03*
X688800Y4100D03*
X680300Y75600D03*
X681600Y55500D03*
X698400Y90300D03*
X689723Y89400D03*
X689311Y96311D03*
X679862Y96538D03*
X677638Y93290D03*
X678288Y122700D03*
X697185Y117385D03*
X687736Y118700D03*
X689961Y122030D03*
X694961D03*
X685600Y133200D03*
X680900D03*
X680612Y129600D03*
X685612D03*
X701100Y16900D03*
X701670Y97100D03*
Y92100D03*
X701732Y101968D03*
X740300Y87300D03*
X735807Y96593D03*
X745256Y96044D03*
X724400Y105600D03*
X729400D03*
X730310Y115390D03*
X725310D03*
X743681Y117400D03*
X731950Y111850D03*
X723500Y118900D03*
X722400Y102300D03*
X730900Y108900D03*
X753100Y75100D03*
X765600Y74800D03*
X761929Y72900D03*
X756929D03*
X752480Y92830D03*
X747480D03*
X764153Y96153D03*
X754704Y96196D03*
X745905Y120452D03*
X750905D03*
X762578Y117300D03*
X753130D03*
X754300Y121400D03*
X764803Y120330D03*
X764000Y124700D03*
X760410Y124730D03*
X755410D03*
X774600Y90300D03*
X778200Y92130D03*
Y97130D03*
X776032Y101968D03*
X772027Y117300D03*
X769803Y120330D03*
X1223200Y99000D03*
X1218000Y99100D03*
X1216500Y119500D03*
X1216700Y114400D03*
X1216500Y108300D03*
X1216400Y102600D03*
X1226900Y119561D03*
Y114043D03*
X1227000Y108361D03*
X1227100Y102861D03*
X1219600Y129400D03*
X1219400Y123900D03*
X1211200Y144900D03*
X1217405Y143895D03*
X1229800Y96400D03*
X1238900Y123300D03*
X1238100Y127900D03*
X1273000Y6100D03*
X1270610Y21960D03*
X1267700Y22900D03*
Y19700D03*
X1268700Y14000D03*
X1268386Y35000D03*
Y46100D03*
X1266811Y78300D03*
X1273111Y89100D03*
X1269961Y78400D03*
X1276700Y5900D03*
X1280900D03*
X1285800D03*
X1278700Y19800D03*
Y23000D03*
X1275610Y21960D03*
X1289775Y11975D03*
X1296600Y35000D03*
X1277700D03*
X1287284D03*
X1296733Y46100D03*
X1287284D03*
X1277835D03*
X1284134D03*
X1280985Y46200D03*
X1295158Y79158D03*
X1292008Y80192D03*
X1288859Y78400D03*
X1279410Y87200D03*
X1285709Y84300D03*
X1276260Y79000D03*
X1282559Y85700D03*
X1315879Y38200D03*
X1315979Y33900D03*
X1317959Y36200D03*
X1323559D03*
X1325279Y38600D03*
Y33800D03*
X1335300Y55600D03*
X1340400Y90800D03*
X1333400Y82900D03*
X1323000Y99239D03*
X1321400Y92800D03*
X1329500Y81400D03*
X1321500Y82600D03*
X1322500Y87800D03*
X1335600Y96500D03*
X1360600Y4000D03*
X1344700Y4100D03*
X1358200Y69000D03*
X1358600Y73700D03*
X1359000Y91000D03*
X1345100Y105500D03*
X1376300Y4000D03*
X1371600Y86463D03*
X1387400Y87242D03*
X1389900Y97600D03*
X1371600Y96000D03*
X1395679Y22600D03*
X1390979Y22500D03*
X1390879Y13800D03*
X1395679Y13900D03*
X1393379Y20580D03*
Y15580D03*
X1395200Y99500D03*
X1391000Y92400D03*
X1433700Y8000D03*
X1429525Y13775D03*
X1417678Y46100D03*
X1427127D03*
X1417678Y35000D03*
X1427000D03*
X1433426Y46100D03*
X1430277D03*
X1416103Y78400D03*
X1422403D03*
X1434200Y88100D03*
X1435001Y81700D03*
X1431851Y80200D03*
X1428702Y79002D03*
X1429400Y88500D03*
X1442400Y8200D03*
X1438000Y8100D03*
X1446300Y8300D03*
X1436500Y23900D03*
Y20700D03*
X1445900Y20800D03*
X1445700Y24400D03*
X1443800Y22500D03*
X1438800D03*
X1454600Y17600D03*
X1446025Y46100D03*
X1436576D03*
X1445900Y35000D03*
X1436576D03*
X1444450Y78300D03*
X1441300Y79100D03*
X1438151Y81100D03*
X1472400Y102700D03*
X1474200Y106600D03*
X1494200Y97800D03*
X1495000Y92800D03*
X1484700Y93057D03*
X1485000Y98057D03*
X1494700Y111200D03*
X1494500Y102700D03*
X1484900Y103257D03*
X1492300Y117558D03*
X1484800Y109357D03*
X1492042Y126358D03*
X1495800Y147800D03*
X1487600Y147000D03*
X1527200Y3800D03*
X1518200Y55600D03*
X1524478Y97100D03*
Y92100D03*
X1521579Y94700D03*
X1521179Y91100D03*
X1534388Y72900D03*
X1529388D03*
X1550500Y75500D03*
X1537279Y75700D03*
X1531679Y75900D03*
X1535300Y55800D03*
X1542716Y93290D03*
X1547716D03*
X1549940Y96538D03*
X1540492Y96486D03*
X1531692Y121000D03*
X1528478Y102500D03*
X1548366Y122700D03*
X1538917Y117661D03*
X1529468Y117490D03*
X1536692Y121000D03*
X1546141Y125930D03*
X1550690Y129600D03*
X1550979Y133200D03*
X1537579Y126200D03*
X1541141Y125930D03*
X1559000Y4200D03*
X1570800Y18900D03*
X1551800Y55700D03*
X1571748Y92100D03*
Y97100D03*
X1559802Y89400D03*
X1559389Y96311D03*
X1568479Y90300D03*
X1571810Y101968D03*
X1557814Y118700D03*
X1567263Y117385D03*
X1565039Y122030D03*
X1560039D03*
X1555690Y129600D03*
X1555679Y133200D03*
X1594478Y105600D03*
X1592900Y101700D03*
X1593300Y119000D03*
X1595388Y115390D03*
X1617558Y92830D03*
X1610379Y87300D03*
X1605885Y96593D03*
X1615334Y96044D03*
X1599478Y105600D03*
X1600388Y115390D03*
X1613759Y117400D03*
X1602028Y111850D03*
X1600900Y108700D03*
X1615983Y120452D03*
X1635679Y74800D03*
X1623179Y75100D03*
X1627007Y72900D03*
X1632007D03*
X1622558Y92830D03*
X1624782Y96196D03*
X1634231Y96153D03*
X1620983Y120452D03*
X1639881Y120330D03*
X1623208Y117300D03*
X1642105D03*
X1632656D03*
X1624300Y121500D03*
X1634881Y120330D03*
X1625488Y124730D03*
X1630488D03*
X1634179Y124300D03*
X1648278Y97130D03*
X1644679Y90300D03*
X1648278Y92130D03*
X1646110Y101968D03*
X1676100Y78900D03*
G54D22*
X123100Y49600D03*
X143300Y27300D03*
X143800Y53600D03*
X144500Y40000D03*
X133100Y71300D03*
X144200Y96300D03*
X143000Y105700D03*
X141900Y154700D03*
X134800Y164000D03*
X144700Y149200D03*
X137100Y158600D03*
X137000Y170400D03*
X127400D03*
X150300Y20200D03*
X166500Y34700D03*
X153100Y49600D03*
X148800Y85000D03*
X163500Y144900D03*
X150300Y144600D03*
X156000Y138200D03*
X156500Y144800D03*
X169900Y146800D03*
X164400Y138200D03*
X169400Y153600D03*
X155600Y157900D03*
X162100Y164300D03*
X168000Y161200D03*
X149300Y164100D03*
X163200Y151600D03*
X162000Y159400D03*
X148000Y158800D03*
X152600Y152000D03*
X155900Y170000D03*
X163800Y170100D03*
X148600D03*
X180300Y20200D03*
X183100Y49600D03*
X191700Y75400D03*
X175000Y62300D03*
X174200Y96300D03*
X190400Y136600D03*
X191200Y142400D03*
X178100Y144600D03*
X184000Y138800D03*
X173600Y138700D03*
X185800Y145400D03*
X190000Y149800D03*
X179300Y156400D03*
X187100Y155800D03*
X192100Y163500D03*
X176300Y164400D03*
X175500Y151300D03*
X173700Y158700D03*
X190400Y169800D03*
X182600Y152000D03*
X171300Y170000D03*
X177800Y170400D03*
X210300Y20200D03*
X213100Y49600D03*
X209400Y60900D03*
X204200Y96300D03*
X196200Y102300D03*
X211300Y138600D03*
X204200Y139200D03*
X195900Y146300D03*
X213300Y146800D03*
X197300Y139100D03*
X205100Y147700D03*
X201500Y154400D03*
X213500Y155400D03*
X197100Y160800D03*
X194600Y154800D03*
X227100Y43000D03*
X234200Y96300D03*
X225600Y104500D03*
X234500Y138700D03*
X230600Y146400D03*
X218100Y140500D03*
X224400Y138200D03*
X236800Y165000D03*
X238800Y157500D03*
X231600Y155100D03*
X221800Y149400D03*
X236500Y185900D03*
X235400Y172900D03*
X240300Y20200D03*
X243100Y49600D03*
X248600Y142900D03*
X242600Y140100D03*
X254400Y138200D03*
X239600Y148700D03*
X245100Y165200D03*
X255400Y148400D03*
X245600Y157000D03*
X248400Y149800D03*
X239800Y178700D03*
X243300Y185600D03*
X242300Y171800D03*
X252600Y192000D03*
X242400Y193300D03*
X270300Y20200D03*
X273100Y49600D03*
X264200Y96300D03*
X262900Y104900D03*
X284400Y138200D03*
X265300Y170000D03*
X282600Y192000D03*
X294200Y96300D03*
X287600Y150000D03*
X292800Y169800D03*
X324200Y96300D03*
X314600Y104100D03*
X310200Y135900D03*
X338300Y162900D03*
Y183800D03*
X359200Y164900D03*
X359100Y184400D03*
X466654Y7874D03*
Y29922D03*
Y24410D03*
Y18898D03*
Y13386D03*
Y51969D03*
Y46457D03*
Y40945D03*
Y35433D03*
X474528Y8268D03*
X482402Y7874D03*
X490276Y8268D03*
X474528Y30315D03*
X482402Y29922D03*
X490276Y30315D03*
X474528Y24803D03*
X482402Y24410D03*
X490276Y24803D03*
X474528Y19292D03*
X482402Y18898D03*
X490276Y19292D03*
X474528Y13780D03*
X482402Y13386D03*
X490276Y13780D03*
X474528Y52362D03*
X482402Y51969D03*
X490276Y52362D03*
X474528Y46851D03*
X482402Y46457D03*
X490276Y46851D03*
X474528Y41339D03*
X482402Y40945D03*
X490276Y41339D03*
X474528Y35827D03*
X482402Y35433D03*
X490276Y35827D03*
X498150Y7874D03*
X506024Y8268D03*
X498150Y29922D03*
X506024Y30315D03*
X498150Y24410D03*
X506024Y24803D03*
X498150Y18898D03*
X506024Y19292D03*
X498150Y13386D03*
X506024Y13780D03*
X498150Y51969D03*
X506024Y52362D03*
X498150Y46457D03*
X506024Y46851D03*
X498150Y40945D03*
X506024Y41339D03*
X498150Y35433D03*
X506024Y35827D03*
X649173Y7874D03*
Y29922D03*
Y24410D03*
Y18898D03*
Y13386D03*
Y51969D03*
Y46457D03*
Y40945D03*
Y35433D03*
X657047Y8268D03*
X664921Y7874D03*
X672795Y8268D03*
X657047Y30315D03*
X664921Y29922D03*
X672795Y30315D03*
X657047Y24803D03*
X664921Y24410D03*
X672795Y24803D03*
X657047Y19292D03*
X664921Y18898D03*
X672795Y19292D03*
X657047Y13780D03*
X664921Y13386D03*
X672795Y13780D03*
X657047Y52362D03*
X664921Y51969D03*
X672795Y52362D03*
X657047Y46851D03*
X664921Y46457D03*
X672795Y46851D03*
X657047Y41339D03*
X664921Y40945D03*
X672795Y41339D03*
X657047Y35827D03*
X664921Y35433D03*
X672795Y35827D03*
X680669Y7874D03*
X688543Y8268D03*
X680669Y29922D03*
X688543Y30315D03*
X680669Y24410D03*
X688543Y24803D03*
X680669Y18898D03*
X688543Y19292D03*
X680669Y13386D03*
X688543Y13780D03*
X680669Y51969D03*
X688543Y52362D03*
X680669Y46457D03*
X688543Y46851D03*
X680669Y40945D03*
X688543Y41339D03*
X680669Y35433D03*
X688543Y35827D03*
X806800Y26700D03*
X810700Y65200D03*
X836800Y26700D03*
X825200Y111700D03*
X840700Y65200D03*
X855200Y111700D03*
X855400Y173000D03*
X866800Y26700D03*
X870700Y65200D03*
X896800Y26700D03*
X900700Y65200D03*
X885200Y111700D03*
X885400Y173000D03*
X926800Y26700D03*
X915200Y111700D03*
X915400Y173000D03*
X930700Y65200D03*
X945200Y111700D03*
X945400Y173000D03*
X956800Y26700D03*
X960700Y65200D03*
X975200Y111700D03*
X975400Y173000D03*
X986800Y26700D03*
X990700Y65200D03*
X1018800Y26300D03*
X1005200Y111700D03*
X1005400Y173000D03*
X1022700Y64800D03*
X1037200Y111300D03*
X1035400Y173000D03*
X1048800Y26300D03*
X1052700Y64800D03*
X1067200Y111300D03*
X1067400Y172600D03*
X1078800Y26300D03*
X1082700Y64800D03*
X1097200Y111300D03*
X1097400Y172600D03*
X1136600Y19700D03*
X1135400Y41000D03*
X1127200Y111300D03*
X1127400Y172600D03*
X1157400D03*
X1336733Y7874D03*
X1344607Y8268D03*
X1336733Y29922D03*
X1344607Y30315D03*
X1336733Y24410D03*
X1344607Y24803D03*
X1336733Y18898D03*
X1344607Y19292D03*
X1336733Y13386D03*
X1344607Y13780D03*
X1336733Y51969D03*
X1344607Y52362D03*
X1336733Y46457D03*
X1344607Y46851D03*
X1336733Y40945D03*
X1344607Y41339D03*
X1336733Y35433D03*
X1344607Y35827D03*
X1352481Y7874D03*
X1360355Y8268D03*
X1352481Y29922D03*
X1360355Y30315D03*
X1352481Y24410D03*
X1360355Y24803D03*
X1352481Y18898D03*
X1360355Y19292D03*
X1352481Y13386D03*
X1360355Y13780D03*
X1352481Y51969D03*
X1360355Y52362D03*
X1352481Y46457D03*
X1360355Y46851D03*
X1352481Y40945D03*
X1360355Y41339D03*
X1352481Y35433D03*
X1360355Y35827D03*
X1368229Y7874D03*
X1376103Y8268D03*
X1368229Y29922D03*
X1376103Y30315D03*
X1368229Y24410D03*
X1376103Y24803D03*
X1368229Y18898D03*
X1376103Y19292D03*
X1368229Y13386D03*
X1376103Y13780D03*
X1368229Y51969D03*
X1376103Y52362D03*
X1368229Y46457D03*
X1376103Y46851D03*
X1368229Y40945D03*
X1376103Y41339D03*
X1368229Y35433D03*
X1376103Y35827D03*
X1519252Y7874D03*
X1527126Y8268D03*
X1519252Y29922D03*
X1527126Y30315D03*
X1519252Y24410D03*
X1527126Y24803D03*
X1519252Y18898D03*
X1527126Y19292D03*
X1519252Y13386D03*
X1527126Y13780D03*
X1519252Y51969D03*
X1527126Y52362D03*
X1519252Y46457D03*
X1527126Y46851D03*
X1519252Y40945D03*
X1527126Y41339D03*
X1519252Y35433D03*
X1527126Y35827D03*
X1535000Y7874D03*
X1542874Y8268D03*
X1550748Y7874D03*
X1535000Y29922D03*
X1542874Y30315D03*
X1550748Y29922D03*
X1535000Y24410D03*
X1542874Y24803D03*
X1550748Y24410D03*
X1535000Y18898D03*
X1542874Y19292D03*
X1550748Y18898D03*
X1535000Y13386D03*
X1542874Y13780D03*
X1550748Y13386D03*
X1535000Y51969D03*
X1542874Y52362D03*
X1550748Y51969D03*
X1535000Y46457D03*
X1542874Y46851D03*
X1550748Y46457D03*
X1535000Y40945D03*
X1542874Y41339D03*
X1550748Y40945D03*
X1535000Y35433D03*
X1542874Y35827D03*
X1550748Y35433D03*
X1558622Y8268D03*
Y30315D03*
Y24803D03*
Y19292D03*
Y13780D03*
Y52362D03*
Y46851D03*
Y41339D03*
Y35827D03*
G54D24*
X343780Y11810D03*
Y19684D03*
Y27558D03*
X335906Y11810D03*
Y19684D03*
Y27558D03*
X343780Y43306D03*
Y51180D03*
X335906Y43306D03*
Y51180D03*
X343780Y59054D03*
X335906D03*
X1205984Y11810D03*
Y19684D03*
Y27558D03*
Y43306D03*
Y51180D03*
Y59054D03*
X1213858Y11810D03*
Y19684D03*
Y27558D03*
Y43306D03*
Y51180D03*
Y59054D03*
G54D10*
X8221Y28000D03*
Y9008D03*
X4287Y18504D03*
X17717Y5074D03*
X27213Y28000D03*
X31147Y18504D03*
X27213Y9008D03*
X17717Y31934D03*
X1661016Y28000D03*
Y9008D03*
X1657082Y18504D03*
X1670512Y5074D03*
X1680008Y28000D03*
X1683942Y18504D03*
X1680008Y9008D03*
X1670512Y31934D03*
G54D29*
X383642Y40532D03*
Y79902D03*
X396122Y99587D03*
X383642Y119272D03*
Y158642D03*
X417382Y99587D03*
X405964Y178327D03*
X439744Y99587D03*
Y138957D03*
Y178327D03*
X532934Y40532D03*
Y79902D03*
Y119272D03*
Y158642D03*
X545414Y99587D03*
X555256Y178327D03*
X566674Y99587D03*
X589036D03*
Y138957D03*
Y178327D03*
X1253721Y40532D03*
Y79902D03*
Y119272D03*
Y158642D03*
X1266201Y99587D03*
X1276043Y178327D03*
X1287461Y99587D03*
X1309823D03*
Y138957D03*
Y178327D03*
X1403012Y40532D03*
Y79902D03*
Y119272D03*
Y158642D03*
X1415492Y99587D03*
X1436752D03*
X1425334Y178327D03*
X1459114Y99587D03*
Y138957D03*
Y178327D03*
G54D31*
X439744Y60217D03*
X589036D03*
X1309823D03*
X1459114D03*
G54D16*
X56339Y41339D03*
Y53150D03*
Y64961D03*
Y76772D03*
Y88583D03*
Y100394D03*
Y112205D03*
Y124016D03*
X44528Y135827D03*
X56339D03*
G54D19*
X85866Y72835D03*
Y104331D03*
G54D14*
X40827Y29528D03*
Y147638D03*
G54D32*
X468859Y115666D03*
Y141650D03*
X488859Y115666D03*
X478859D03*
X483859Y125666D03*
X473859D03*
X478859Y141650D03*
X488859D03*
X473859Y151650D03*
X483859D03*
X498859Y115666D03*
X503859Y125666D03*
X493859D03*
X498859Y141650D03*
X493859Y151650D03*
X503859D03*
X1338938Y115666D03*
X1343938Y125666D03*
X1338938Y141650D03*
X1343938Y151650D03*
X1358938Y115666D03*
X1348938D03*
X1363938Y125666D03*
X1353938D03*
X1348938Y141650D03*
X1358938D03*
X1353938Y151650D03*
X1363938D03*
X1368938Y115666D03*
X1373938Y125666D03*
X1368938Y141650D03*
X1373938Y151650D03*
G54D36*
X641212Y132244D03*
X791764D03*
X1511291D03*
X1661843D03*
G54D11*
X9088Y80158D03*
Y91958D03*
X19088Y80158D03*
Y91958D03*
X109288Y92458D03*
X119288D03*
X109288Y103958D03*
X119288D03*
G54D27*
X392776Y32264D03*
X383642Y50375D03*
Y70060D03*
Y88564D03*
X411673Y32264D03*
X430571D03*
X439744Y50375D03*
Y70060D03*
Y88564D03*
X532934Y50375D03*
Y70060D03*
Y88564D03*
X542068Y32264D03*
X560965D03*
X579863D03*
X589036Y50375D03*
Y70060D03*
Y88564D03*
X1262855Y32264D03*
X1253721Y50375D03*
Y70060D03*
Y88564D03*
X1281752Y32264D03*
X1300650D03*
X1309823Y50375D03*
Y70060D03*
Y88564D03*
X1412146Y32264D03*
X1403012Y50375D03*
Y70060D03*
Y88564D03*
X1431043Y32264D03*
X1449941D03*
X1459114Y50375D03*
Y70060D03*
Y88564D03*
G54D28*
X392795Y56653D03*
X542087Y56654D03*
X655453Y132244D03*
X702697D03*
X730295D03*
X777539D03*
X1262874Y56654D03*
X1412166Y56653D03*
X1525531Y132244D03*
X1572775D03*
X1600374D03*
X1647618D03*
G54D20*
X81929Y76772D03*
Y68898D03*
X89803Y76772D03*
Y68898D03*
X81929Y100394D03*
Y92520D03*
Y84646D03*
X89803Y100394D03*
Y92520D03*
Y84646D03*
X81929Y108268D03*
X89803D03*
G54D17*
X51900Y162300D03*
X53200Y169500D03*
X76900Y20200D03*
X65600Y160400D03*
X57200Y165300D03*
X73200Y162100D03*
X62200Y169900D03*
X70400Y170000D03*
X90200Y22400D03*
X94900Y144500D03*
X83800Y154500D03*
X99000Y148900D03*
X78800Y158000D03*
X93900Y162900D03*
X90200Y169500D03*
X81600Y162600D03*
X92600Y154800D03*
X100700Y163400D03*
X89000Y150200D03*
X88000Y158900D03*
X83500Y169700D03*
X78200Y169900D03*
X96900Y169500D03*
X98000Y157100D03*
X102500Y29400D03*
X107200Y19300D03*
X121200Y33900D03*
X102000Y141900D03*
X114000Y145200D03*
X119900Y143200D03*
X108600Y143100D03*
X111800Y151800D03*
X104900Y157400D03*
X120500Y157200D03*
X111900Y164800D03*
X118100Y162100D03*
X104500Y150300D03*
X110900Y159200D03*
X118400Y152000D03*
X106500Y170300D03*
X115300Y170200D03*
X123900Y41000D03*
X138700Y63500D03*
X144100Y72900D03*
X139800Y90200D03*
X131400Y91300D03*
X129200Y101300D03*
Y142400D03*
X126600Y149500D03*
X165600Y19400D03*
X168100Y48400D03*
X151500Y35800D03*
X159800Y65100D03*
X161800Y86800D03*
X158200Y102400D03*
X184100Y36600D03*
X174300Y73300D03*
X181400Y84700D03*
X194400Y20200D03*
X197800Y30900D03*
Y48000D03*
X214700Y35800D03*
X195600Y64100D03*
X206700Y72700D03*
X225800Y19600D03*
X229200Y30900D03*
X216400Y100500D03*
X254400Y19200D03*
X257800Y51200D03*
X244900Y36600D03*
X254400Y74300D03*
X251600Y100100D03*
X252200Y159400D03*
X252800Y179900D03*
X268300Y36200D03*
X283600Y69500D03*
X273300Y94900D03*
X281800Y100900D03*
X267700Y145200D03*
X280000Y159800D03*
X281000Y180700D03*
X307800Y101100D03*
X300300Y140000D03*
X350000Y161800D03*
X350200Y181100D03*
X813700Y43900D03*
X809700Y86500D03*
X839700D03*
X838300Y128100D03*
X855400Y152400D03*
X857000Y189800D03*
X869700Y86500D03*
X868300Y128100D03*
X899700Y86500D03*
X898300Y128100D03*
X885400Y152400D03*
X887000Y189800D03*
X929700Y86500D03*
X928300Y128100D03*
X915400Y152400D03*
X917000Y189800D03*
X945400Y152400D03*
X947000Y189800D03*
X959000Y18000D03*
X959700Y86500D03*
X958300Y128100D03*
X975400Y152400D03*
X989700Y86500D03*
X988300Y128100D03*
X977000Y189800D03*
X1018300Y128100D03*
X1005400Y152400D03*
X1007000Y189800D03*
X1043000Y45500D03*
X1031900Y84100D03*
X1035400Y152400D03*
X1037000Y189800D03*
X1063700Y15300D03*
X1061900Y84100D03*
X1048300Y128100D03*
X1065400Y152400D03*
X1067000Y189800D03*
X1073000Y45500D03*
X1078300Y128100D03*
X1091900Y84100D03*
X1108300Y128100D03*
X1095400Y152400D03*
X1097000Y189800D03*
X1120900Y64500D03*
X1121900Y84100D03*
X1125400Y152400D03*
X1127000Y189800D03*
X1147100Y64500D03*
X1151900Y84100D03*
X1155400Y152400D03*
X1157000Y189800D03*
G54D26*
X367402Y11810D03*
Y19684D03*
Y27558D03*
X359528Y11810D03*
Y19684D03*
Y27558D03*
X367402Y43306D03*
Y51180D03*
X359528Y43306D03*
Y51180D03*
X367402Y59054D03*
X359528D03*
X1229606Y11810D03*
Y19684D03*
Y27558D03*
Y43306D03*
Y51180D03*
Y59054D03*
X1237480Y11810D03*
Y19684D03*
Y27558D03*
Y43306D03*
Y51180D03*
Y59054D03*
G54D15*
X44528Y41339D03*
Y53150D03*
Y64961D03*
Y76772D03*
Y88583D03*
Y100394D03*
Y112205D03*
Y124016D03*
G54D33*
X452875Y131650D03*
X455867Y153658D03*
X452875Y194642D03*
X516851Y140666D03*
X519843Y115666D03*
Y194642D03*
X1322954Y131650D03*
Y194642D03*
X1325946Y153658D03*
X1389922Y115666D03*
X1386930Y140666D03*
X1389922Y194642D03*
G54D25*
X351654Y37400D03*
X1221732D03*
G54D12*
X17717Y18504D03*
X1670512D03*
G54D35*
X639283Y108622D03*
Y167677D03*
X793693Y108622D03*
Y167677D03*
X1509362Y108622D03*
Y167677D03*
X1663772Y108622D03*
Y167677D03*
G54D34*
X463859Y176650D03*
X508859D03*
X1333938D03*
X1378938D03*
G54D13*
X17716Y114173D03*
X314213Y163386D03*
X783661Y18504D03*
X826024Y163386D03*
X1101615Y18504D03*
X1184292Y163386D03*
G54D30*
X430591Y56653D03*
X579883Y56654D03*
X1300670D03*
X1449962Y56653D03*
G54D23*
X306772Y19685D03*
Y41850D03*
Y67913D03*
X612047Y19685D03*
Y41850D03*
Y67913D03*
X1176851Y19685D03*
Y41850D03*
Y67913D03*
X1482126Y19685D03*
Y41850D03*
Y67913D03*
G54D18*
X64500Y165200D03*
X89400Y165300D03*
X122758Y82442D03*
X117158Y82542D03*
X112158Y82342D03*
X106958Y82142D03*
X105800Y165400D03*
X125558Y79642D03*
X526612Y142000D03*
%LPC*%
G75*
G54D37*
G01X457212Y-338900D02*
Y-343900D01*
G01X455755Y-338900D02*
X458669D01*
G01X463579Y-343900D02*
X461045D01*
Y-338900D01*
X463579D01*
G01X462565Y-341317D02*
X461045D01*
G01X466145Y-338900D02*
Y-343900D01*
X468679D01*
G01X472512Y-344067D02*
X472385Y-343983D01*
Y-343817D01*
X472512Y-343733D01*
X472639Y-343817D01*
Y-343983D01*
X472512Y-344067D01*
G01Y-341817D02*
X472385Y-341733D01*
Y-341567D01*
X472512Y-341483D01*
X472639Y-341567D01*
Y-341733D01*
X472512Y-341817D01*
G01X477295Y-345567D02*
X476662Y-344733D01*
X476345Y-343900D01*
Y-340567D01*
X476662Y-339733D01*
X477295Y-338900D01*
G01X482712D02*
X482205Y-339067D01*
X481825Y-339483D01*
X481572Y-339983D01*
X481382Y-340650D01*
X481319Y-341400D01*
X481382Y-342150D01*
X481572Y-342817D01*
X481825Y-343317D01*
X482205Y-343733D01*
X482712Y-343900D01*
X483219Y-343733D01*
X483599Y-343317D01*
X483852Y-342817D01*
X484042Y-342150D01*
X484105Y-341400D01*
X484042Y-340650D01*
X483852Y-339983D01*
X483599Y-339483D01*
X483219Y-339067D01*
X482712Y-338900D01*
G01X486419Y-342900D02*
X486799Y-343483D01*
X487305Y-343817D01*
X487875Y-343900D01*
X488382Y-343817D01*
X488889Y-343400D01*
X489205Y-342900D01*
X489269Y-342400D01*
X489142Y-341817D01*
X488699Y-341400D01*
X488255Y-341233D01*
X487685D01*
G01X488255D02*
X488635Y-340983D01*
X488952Y-340567D01*
X489079Y-340067D01*
X488952Y-339567D01*
X488635Y-339150D01*
X488065Y-338900D01*
X487495Y-338983D01*
X486925Y-339317D01*
G01X493229Y-345567D02*
X493862Y-344733D01*
X494179Y-343900D01*
Y-340567D01*
X493862Y-339733D01*
X493229Y-338900D01*
G01X496619Y-342900D02*
X496999Y-343483D01*
X497505Y-343817D01*
X498075Y-343900D01*
X498582Y-343817D01*
X499089Y-343400D01*
X499405Y-342900D01*
X499469Y-342400D01*
X499342Y-341817D01*
X498899Y-341400D01*
X498455Y-341233D01*
X497885D01*
G01X498455D02*
X498835Y-340983D01*
X499152Y-340567D01*
X499279Y-340067D01*
X499152Y-339567D01*
X498835Y-339150D01*
X498265Y-338900D01*
X497695Y-338983D01*
X497125Y-339317D01*
G01X501909Y-339733D02*
X502289Y-339233D01*
X502732Y-338983D01*
X503239Y-338900D01*
X503872Y-339067D01*
X504315Y-339483D01*
X504442Y-339983D01*
X504379Y-340483D01*
X504125Y-340900D01*
X502859Y-341733D01*
X502289Y-342317D01*
X501909Y-343150D01*
X501782Y-343900D01*
X504442D01*
G01X508085D02*
X508212Y-342817D01*
X508402Y-341900D01*
X508655Y-341067D01*
X508972Y-340150D01*
X509479Y-338900D01*
X506945D01*
G01X512489Y-342233D02*
X514135D01*
G01X517209Y-339733D02*
X517589Y-339233D01*
X518032Y-338983D01*
X518539Y-338900D01*
X519172Y-339067D01*
X519615Y-339483D01*
X519742Y-339983D01*
X519679Y-340483D01*
X519425Y-340900D01*
X518159Y-341733D01*
X517589Y-342317D01*
X517209Y-343150D01*
X517082Y-343900D01*
X519742D01*
G01X522119Y-342900D02*
X522499Y-343483D01*
X523005Y-343817D01*
X523575Y-343900D01*
X524082Y-343817D01*
X524589Y-343400D01*
X524905Y-342900D01*
X524969Y-342400D01*
X524842Y-341817D01*
X524399Y-341400D01*
X523955Y-341233D01*
X523385D01*
G01X523955D02*
X524335Y-340983D01*
X524652Y-340567D01*
X524779Y-340067D01*
X524652Y-339567D01*
X524335Y-339150D01*
X523765Y-338900D01*
X523195Y-338983D01*
X522625Y-339317D01*
G01X529372Y-343900D02*
Y-338900D01*
X527029Y-342483D01*
X530195D01*
G01X532319Y-343150D02*
X532699Y-343567D01*
X533142Y-343817D01*
X533712Y-343900D01*
X534282Y-343733D01*
X534725Y-343400D01*
X535042Y-342817D01*
X535105Y-342150D01*
X534979Y-341483D01*
X534662Y-341067D01*
X534219Y-340733D01*
X533775Y-340650D01*
X533332Y-340733D01*
X532762Y-341067D01*
X532952Y-338900D01*
X534662D01*
G01X542709Y-343900D02*
Y-338900D01*
X545115D01*
G01X544229Y-341317D02*
X542709D01*
G01X547429Y-343900D02*
X549012Y-338900D01*
X550595Y-343900D01*
G01X550025Y-342150D02*
X547999D01*
G01X552782Y-343900D02*
X555442Y-338900D01*
G01X552782D02*
X555442Y-343900D01*
G01X559212Y-344067D02*
X559085Y-343983D01*
Y-343817D01*
X559212Y-343733D01*
X559339Y-343817D01*
Y-343983D01*
X559212Y-344067D01*
G01Y-341817D02*
X559085Y-341733D01*
Y-341567D01*
X559212Y-341483D01*
X559339Y-341567D01*
Y-341733D01*
X559212Y-341817D01*
G01X563995Y-345567D02*
X563362Y-344733D01*
X563045Y-343900D01*
Y-340567D01*
X563362Y-339733D01*
X563995Y-338900D01*
G01X569412D02*
X568905Y-339067D01*
X568525Y-339483D01*
X568272Y-339983D01*
X568082Y-340650D01*
X568019Y-341400D01*
X568082Y-342150D01*
X568272Y-342817D01*
X568525Y-343317D01*
X568905Y-343733D01*
X569412Y-343900D01*
X569919Y-343733D01*
X570299Y-343317D01*
X570552Y-342817D01*
X570742Y-342150D01*
X570805Y-341400D01*
X570742Y-340650D01*
X570552Y-339983D01*
X570299Y-339483D01*
X569919Y-339067D01*
X569412Y-338900D01*
G01X573119Y-342900D02*
X573499Y-343483D01*
X574005Y-343817D01*
X574575Y-343900D01*
X575082Y-343817D01*
X575589Y-343400D01*
X575905Y-342900D01*
X575969Y-342400D01*
X575842Y-341817D01*
X575399Y-341400D01*
X574955Y-341233D01*
X574385D01*
G01X574955D02*
X575335Y-340983D01*
X575652Y-340567D01*
X575779Y-340067D01*
X575652Y-339567D01*
X575335Y-339150D01*
X574765Y-338900D01*
X574195Y-338983D01*
X573625Y-339317D01*
G01X579929Y-345567D02*
X580562Y-344733D01*
X580879Y-343900D01*
Y-340567D01*
X580562Y-339733D01*
X579929Y-338900D01*
G01X583319Y-342900D02*
X583699Y-343483D01*
X584205Y-343817D01*
X584775Y-343900D01*
X585282Y-343817D01*
X585789Y-343400D01*
X586105Y-342900D01*
X586169Y-342400D01*
X586042Y-341817D01*
X585599Y-341400D01*
X585155Y-341233D01*
X584585D01*
G01X585155D02*
X585535Y-340983D01*
X585852Y-340567D01*
X585979Y-340067D01*
X585852Y-339567D01*
X585535Y-339150D01*
X584965Y-338900D01*
X584395Y-338983D01*
X583825Y-339317D01*
G01X588735Y-343317D02*
X589179Y-343733D01*
X589685Y-343900D01*
X590192Y-343733D01*
X590635Y-343233D01*
X590952Y-342483D01*
X591079Y-341733D01*
Y-340817D01*
X590952Y-340067D01*
X590635Y-339400D01*
X590255Y-339067D01*
X589812Y-338900D01*
X589305Y-339067D01*
X588925Y-339400D01*
X588672Y-339900D01*
X588545Y-340567D01*
X588672Y-341150D01*
X588989Y-341733D01*
X589369Y-342067D01*
X589812Y-342150D01*
X590319Y-341983D01*
X590699Y-341567D01*
X591079Y-340817D01*
G01X594785Y-343900D02*
X594912Y-342817D01*
X595102Y-341900D01*
X595355Y-341067D01*
X595672Y-340150D01*
X596179Y-338900D01*
X593645D01*
G01X599189Y-342233D02*
X600835D01*
G01X603719Y-342900D02*
X604099Y-343483D01*
X604605Y-343817D01*
X605175Y-343900D01*
X605682Y-343817D01*
X606189Y-343400D01*
X606505Y-342900D01*
X606569Y-342400D01*
X606442Y-341817D01*
X605999Y-341400D01*
X605555Y-341233D01*
X604985D01*
G01X605555D02*
X605935Y-340983D01*
X606252Y-340567D01*
X606379Y-340067D01*
X606252Y-339567D01*
X605935Y-339150D01*
X605365Y-338900D01*
X604795Y-338983D01*
X604225Y-339317D01*
G01X609009Y-341817D02*
X609452Y-341233D01*
X609832Y-340900D01*
X610339Y-340733D01*
X610782Y-340900D01*
X611099Y-341233D01*
X611352Y-341733D01*
X611415Y-342317D01*
X611352Y-342817D01*
X611099Y-343317D01*
X610719Y-343733D01*
X610275Y-343900D01*
X609769Y-343733D01*
X609325Y-343233D01*
X609072Y-342483D01*
X609009Y-341650D01*
X609135Y-340567D01*
X609325Y-339983D01*
X609642Y-339400D01*
X610085Y-338983D01*
X610529Y-338900D01*
X610972Y-339067D01*
X611289Y-339483D01*
G01X615312Y-343900D02*
Y-338900D01*
X614552Y-339900D01*
G01Y-343900D02*
X616072D01*
G01X621172D02*
Y-338900D01*
X618829Y-342483D01*
X621995D01*
G01X445212Y-273900D02*
Y-348900D01*
X945212D01*
Y-273900D01*
X445212D01*
G01X640212D02*
Y-348900D01*
G01Y-323900D02*
X743212D01*
Y-298900D01*
G01X640212D02*
X743212D01*
G01Y-273900D02*
Y-348900D01*
G01X745212Y-273900D02*
Y-348900D01*
G01X750719Y-333900D02*
Y-328900D01*
X751985D01*
X752492Y-329150D01*
X752872Y-329483D01*
X753189Y-329983D01*
X753442Y-330567D01*
X753505Y-331400D01*
X753442Y-332233D01*
X753189Y-332817D01*
X752872Y-333317D01*
X752492Y-333650D01*
X751985Y-333900D01*
X750719D01*
G01X755629D02*
X757212Y-328900D01*
X758795Y-333900D01*
G01X758225Y-332150D02*
X756199D01*
G01X762312Y-328900D02*
Y-333900D01*
G01X760855Y-328900D02*
X763769D01*
G01X768679Y-333900D02*
X766145D01*
Y-328900D01*
X768679D01*
G01X767665Y-331317D02*
X766145D01*
G01X772512Y-334067D02*
X772385Y-333983D01*
Y-333817D01*
X772512Y-333733D01*
X772639Y-333817D01*
Y-333983D01*
X772512Y-334067D01*
G01Y-331817D02*
X772385Y-331733D01*
Y-331567D01*
X772512Y-331483D01*
X772639Y-331567D01*
Y-331733D01*
X772512Y-331817D01*
G01X745212Y-323900D02*
X945212D01*
G01X750845Y-308900D02*
Y-303900D01*
X752365D01*
X752872Y-304150D01*
X753252Y-304733D01*
X753379Y-305400D01*
X753252Y-306067D01*
X752935Y-306567D01*
X752365Y-306817D01*
X750845D01*
G01X756072Y-309067D02*
X758352Y-303900D01*
G01X760855Y-308900D02*
Y-303900D01*
X763769Y-308900D01*
Y-303900D01*
G01X767412Y-309067D02*
X767285Y-308983D01*
Y-308817D01*
X767412Y-308733D01*
X767539Y-308817D01*
Y-308983D01*
X767412Y-309067D01*
G01Y-306817D02*
X767285Y-306733D01*
Y-306567D01*
X767412Y-306483D01*
X767539Y-306567D01*
Y-306733D01*
X767412Y-306817D01*
G01X745212Y-298900D02*
X945212D01*
G01X750845Y-283900D02*
Y-278900D01*
X752365D01*
X752872Y-279150D01*
X753252Y-279733D01*
X753379Y-280400D01*
X753252Y-281067D01*
X752935Y-281567D01*
X752365Y-281817D01*
X750845D01*
G01X755945Y-283900D02*
Y-278900D01*
X757529D01*
X758035Y-279150D01*
X758352Y-279483D01*
X758479Y-280150D01*
X758352Y-280817D01*
X757972Y-281233D01*
X757529Y-281483D01*
X755945D01*
G01X757529D02*
X758479Y-283900D01*
G01X762312D02*
X761805Y-283817D01*
X761362Y-283483D01*
X760982Y-282983D01*
X760729Y-282400D01*
X760602Y-281733D01*
Y-281067D01*
X760729Y-280400D01*
X760982Y-279817D01*
X761362Y-279317D01*
X761805Y-278983D01*
X762312Y-278900D01*
X762819Y-278983D01*
X763262Y-279317D01*
X763642Y-279817D01*
X763895Y-280400D01*
X764022Y-281067D01*
Y-281733D01*
X763895Y-282400D01*
X763642Y-282983D01*
X763262Y-283483D01*
X762819Y-283817D01*
X762312Y-283900D01*
G01X766145Y-282900D02*
X766462Y-283400D01*
X766842Y-283733D01*
X767285Y-283900D01*
X767792Y-283733D01*
X768172Y-283400D01*
X768552Y-282900D01*
X768679Y-282233D01*
Y-278900D01*
G01X773779Y-283900D02*
X771245D01*
Y-278900D01*
X773779D01*
G01X772765Y-281317D02*
X771245D01*
G01X779005Y-279317D02*
X778625Y-279067D01*
X778182Y-278900D01*
X777675D01*
X777105Y-279150D01*
X776662Y-279567D01*
X776345Y-280067D01*
X776092Y-280900D01*
X776029Y-281650D01*
X776155Y-282400D01*
X776345Y-282900D01*
X776725Y-283400D01*
X777169Y-283733D01*
X777612Y-283900D01*
X778055D01*
X778499Y-283733D01*
X778879Y-283483D01*
X779195Y-283150D01*
G01X782712Y-278900D02*
Y-283900D01*
G01X781255Y-278900D02*
X784169D01*
G01X787812Y-284067D02*
X787685Y-283983D01*
Y-283817D01*
X787812Y-283733D01*
X787939Y-283817D01*
Y-283983D01*
X787812Y-284067D01*
G01Y-281817D02*
X787685Y-281733D01*
Y-281567D01*
X787812Y-281483D01*
X787939Y-281567D01*
Y-281733D01*
X787812Y-281817D01*
G01X860212Y-323900D02*
Y-348900D01*
G01X865845Y-333900D02*
Y-328900D01*
X867429D01*
X867935Y-329150D01*
X868252Y-329483D01*
X868379Y-330150D01*
X868252Y-330817D01*
X867872Y-331233D01*
X867429Y-331483D01*
X865845D01*
G01X867429D02*
X868379Y-333900D01*
G01X873479D02*
X870945D01*
Y-328900D01*
X873479D01*
G01X872465Y-331317D02*
X870945D01*
G01X875729Y-328900D02*
X877312Y-333900D01*
X878895Y-328900D01*
G01X882412Y-334067D02*
X882285Y-333983D01*
Y-333817D01*
X882412Y-333733D01*
X882539Y-333817D01*
Y-333983D01*
X882412Y-334067D01*
G01Y-331817D02*
X882285Y-331733D01*
Y-331567D01*
X882412Y-331483D01*
X882539Y-331567D01*
Y-331733D01*
X882412Y-331817D01*
G01X909212Y-323900D02*
Y-348900D01*
G01X-471400Y-391900D02*
Y1528800D01*
X2244200D01*
Y-391900D01*
X-471400D01*
G01X455917Y-335560D02*
X456544Y-336085D01*
X457249Y-336400D01*
X457875D01*
X458502Y-336085D01*
X458972Y-335560D01*
X459207Y-334825D01*
X459050Y-334090D01*
X458659Y-333460D01*
X457954Y-333040D01*
X457014Y-332830D01*
X456465Y-332410D01*
X456230Y-331675D01*
X456387Y-330940D01*
X456779Y-330415D01*
X457327Y-330100D01*
X457875D01*
X458424Y-330310D01*
X458894Y-330835D01*
G01X462217Y-336400D02*
Y-330100D01*
G01X465507D02*
Y-336400D01*
G01Y-333250D02*
X462217D01*
G01X469222Y-330100D02*
X471102D01*
G01X470162D02*
Y-336400D01*
G01X469222D02*
X471102D01*
G01X478029D02*
X474895D01*
Y-330100D01*
X478029D01*
G01X476775Y-333145D02*
X474895D01*
G01X480960Y-336400D02*
Y-330100D01*
X484564Y-336400D01*
Y-330100D01*
G01X488905Y-337555D02*
X489219Y-336190D01*
G01X495362Y-330100D02*
Y-336400D01*
G01X493560Y-330100D02*
X497164D01*
G01X499704Y-336400D02*
X501662Y-330100D01*
X503620Y-336400D01*
G01X502915Y-334195D02*
X500409D01*
G01X507022Y-330100D02*
X508902D01*
G01X507962D02*
Y-336400D01*
G01X507022D02*
X508902D01*
G01X511912Y-330100D02*
X513009Y-336400D01*
X514262Y-330100D01*
X515515Y-336400D01*
X516612Y-330100D01*
G01X518604Y-336400D02*
X520562Y-330100D01*
X522520Y-336400D01*
G01X521815Y-334195D02*
X519309D01*
G01X525060Y-336400D02*
Y-330100D01*
X528664Y-336400D01*
Y-330100D01*
G01X537895Y-336400D02*
Y-330100D01*
X539854D01*
X540480Y-330415D01*
X540872Y-330835D01*
X541029Y-331675D01*
X540872Y-332515D01*
X540402Y-333040D01*
X539854Y-333355D01*
X537895D01*
G01X539854D02*
X541029Y-336400D01*
G01X545762Y-336610D02*
X545605Y-336505D01*
Y-336295D01*
X545762Y-336190D01*
X545919Y-336295D01*
Y-336505D01*
X545762Y-336610D01*
G01X552062Y-336400D02*
X551435Y-336295D01*
X550887Y-335875D01*
X550417Y-335245D01*
X550104Y-334510D01*
X549947Y-333670D01*
Y-332830D01*
X550104Y-331990D01*
X550417Y-331255D01*
X550887Y-330625D01*
X551435Y-330205D01*
X552062Y-330100D01*
X552689Y-330205D01*
X553237Y-330625D01*
X553707Y-331255D01*
X554020Y-331990D01*
X554177Y-332830D01*
Y-333670D01*
X554020Y-334510D01*
X553707Y-335245D01*
X553237Y-335875D01*
X552689Y-336295D01*
X552062Y-336400D01*
G01X558362Y-336610D02*
X558205Y-336505D01*
Y-336295D01*
X558362Y-336190D01*
X558519Y-336295D01*
Y-336505D01*
X558362Y-336610D01*
G01X566385Y-330625D02*
X565915Y-330310D01*
X565367Y-330100D01*
X564740D01*
X564035Y-330415D01*
X563487Y-330940D01*
X563095Y-331570D01*
X562782Y-332620D01*
X562704Y-333565D01*
X562860Y-334510D01*
X563095Y-335140D01*
X563565Y-335770D01*
X564114Y-336190D01*
X564662Y-336400D01*
X565210D01*
X565759Y-336190D01*
X566229Y-335875D01*
X566620Y-335455D01*
G01X570962Y-336610D02*
X570805Y-336505D01*
Y-336295D01*
X570962Y-336190D01*
X571119Y-336295D01*
Y-336505D01*
X570962Y-336610D01*
G01X455839Y-326400D02*
Y-320100D01*
G01X458815D02*
X455839Y-323985D01*
G01X459285Y-326400D02*
X457170Y-322200D01*
G01X462139Y-320100D02*
Y-324615D01*
X462452Y-325560D01*
X463079Y-326190D01*
X463862Y-326400D01*
X464645Y-326190D01*
X465272Y-325560D01*
X465585Y-324615D01*
Y-320100D01*
G01X471729Y-326400D02*
X468595D01*
Y-320100D01*
X471729D01*
G01X470475Y-323145D02*
X468595D01*
G01X475522Y-320100D02*
X477402D01*
G01X476462D02*
Y-326400D01*
G01X475522D02*
X477402D01*
G01X487417Y-325560D02*
X488044Y-326085D01*
X488749Y-326400D01*
X489375D01*
X490002Y-326085D01*
X490472Y-325560D01*
X490707Y-324825D01*
X490550Y-324090D01*
X490159Y-323460D01*
X489454Y-323040D01*
X488514Y-322830D01*
X487965Y-322410D01*
X487730Y-321675D01*
X487887Y-320940D01*
X488279Y-320415D01*
X488827Y-320100D01*
X489375D01*
X489924Y-320310D01*
X490394Y-320835D01*
G01X493717Y-326400D02*
Y-320100D01*
G01X497007D02*
Y-326400D01*
G01Y-323250D02*
X493717D01*
G01X499704Y-326400D02*
X501662Y-320100D01*
X503620Y-326400D01*
G01X502915Y-324195D02*
X500409D01*
G01X506160Y-326400D02*
Y-320100D01*
X509764Y-326400D01*
Y-320100D01*
G01X518917Y-326400D02*
Y-320100D01*
G01X522207D02*
Y-326400D01*
G01Y-323250D02*
X518917D01*
G01X525217Y-325560D02*
X525844Y-326085D01*
X526549Y-326400D01*
X527175D01*
X527802Y-326085D01*
X528272Y-325560D01*
X528507Y-324825D01*
X528350Y-324090D01*
X527959Y-323460D01*
X527254Y-323040D01*
X526314Y-322830D01*
X525765Y-322410D01*
X525530Y-321675D01*
X525687Y-320940D01*
X526079Y-320415D01*
X526627Y-320100D01*
X527175D01*
X527724Y-320310D01*
X528194Y-320835D01*
G01X532222Y-320100D02*
X534102D01*
G01X533162D02*
Y-326400D01*
G01X532222D02*
X534102D01*
G01X537504D02*
X539462Y-320100D01*
X541420Y-326400D01*
G01X540715Y-324195D02*
X538209D01*
G01X543960Y-326400D02*
Y-320100D01*
X547564Y-326400D01*
Y-320100D01*
G01X552532Y-323250D02*
X554099D01*
Y-325140D01*
X553629Y-325770D01*
X553080Y-326190D01*
X552297Y-326400D01*
X551514Y-326190D01*
X550965Y-325770D01*
X550495Y-325140D01*
X550182Y-324405D01*
X550025Y-323565D01*
Y-322830D01*
X550182Y-322200D01*
X550495Y-321465D01*
X550965Y-320835D01*
X551435Y-320415D01*
X552062Y-320100D01*
X552610D01*
X553237Y-320310D01*
X553707Y-320730D01*
G01X558205Y-327555D02*
X558519Y-326190D01*
G01X564662Y-320100D02*
Y-326400D01*
G01X562860Y-320100D02*
X566464D01*
G01X569004Y-326400D02*
X570962Y-320100D01*
X572920Y-326400D01*
G01X572215Y-324195D02*
X569709D01*
G01X577262Y-326400D02*
X576635Y-326295D01*
X576087Y-325875D01*
X575617Y-325245D01*
X575304Y-324510D01*
X575147Y-323670D01*
Y-322830D01*
X575304Y-321990D01*
X575617Y-321255D01*
X576087Y-320625D01*
X576635Y-320205D01*
X577262Y-320100D01*
X577889Y-320205D01*
X578437Y-320625D01*
X578907Y-321255D01*
X579220Y-321990D01*
X579377Y-322830D01*
Y-323670D01*
X579220Y-324510D01*
X578907Y-325245D01*
X578437Y-325875D01*
X577889Y-326295D01*
X577262Y-326400D01*
G01X589862D02*
Y-323565D01*
X588295Y-320100D01*
G01X591429D02*
X589862Y-323565D01*
G01X594439Y-320100D02*
Y-324615D01*
X594752Y-325560D01*
X595379Y-326190D01*
X596162Y-326400D01*
X596945Y-326190D01*
X597572Y-325560D01*
X597885Y-324615D01*
Y-320100D01*
G01X600504Y-326400D02*
X602462Y-320100D01*
X604420Y-326400D01*
G01X603715Y-324195D02*
X601209D01*
G01X606960Y-326400D02*
Y-320100D01*
X610564Y-326400D01*
Y-320100D01*
G01X455760Y-316400D02*
Y-310100D01*
X459364Y-316400D01*
Y-310100D01*
G01X463862Y-316400D02*
X463235Y-316295D01*
X462687Y-315875D01*
X462217Y-315245D01*
X461904Y-314510D01*
X461747Y-313670D01*
Y-312830D01*
X461904Y-311990D01*
X462217Y-311255D01*
X462687Y-310625D01*
X463235Y-310205D01*
X463862Y-310100D01*
X464489Y-310205D01*
X465037Y-310625D01*
X465507Y-311255D01*
X465820Y-311990D01*
X465977Y-312830D01*
Y-313670D01*
X465820Y-314510D01*
X465507Y-315245D01*
X465037Y-315875D01*
X464489Y-316295D01*
X463862Y-316400D01*
G01X470162Y-316610D02*
X470005Y-316505D01*
Y-316295D01*
X470162Y-316190D01*
X470319Y-316295D01*
Y-316505D01*
X470162Y-316610D01*
G01X476462Y-316400D02*
Y-310100D01*
X475522Y-311360D01*
G01Y-316400D02*
X477402D01*
G01X482762D02*
X483310Y-316295D01*
X483937Y-315980D01*
X484329Y-315455D01*
X484485Y-314720D01*
X484329Y-313985D01*
X483859Y-313355D01*
X483154Y-313040D01*
X482370D01*
X481900Y-312830D01*
X481509Y-312305D01*
X481352Y-311570D01*
X481587Y-310835D01*
X482135Y-310310D01*
X482762Y-310100D01*
X483389Y-310310D01*
X483937Y-310835D01*
X484172Y-311570D01*
X484015Y-312305D01*
X483624Y-312830D01*
X483154Y-313040D01*
X482370D01*
X481665Y-313355D01*
X481195Y-313985D01*
X481039Y-314720D01*
X481195Y-315455D01*
X481587Y-315980D01*
X482214Y-316295D01*
X482762Y-316400D01*
G01X489062D02*
X489610Y-316295D01*
X490237Y-315980D01*
X490629Y-315455D01*
X490785Y-314720D01*
X490629Y-313985D01*
X490159Y-313355D01*
X489454Y-313040D01*
X488670D01*
X488200Y-312830D01*
X487809Y-312305D01*
X487652Y-311570D01*
X487887Y-310835D01*
X488435Y-310310D01*
X489062Y-310100D01*
X489689Y-310310D01*
X490237Y-310835D01*
X490472Y-311570D01*
X490315Y-312305D01*
X489924Y-312830D01*
X489454Y-313040D01*
X488670D01*
X487965Y-313355D01*
X487495Y-313985D01*
X487339Y-314720D01*
X487495Y-315455D01*
X487887Y-315980D01*
X488514Y-316295D01*
X489062Y-316400D01*
G01X495205Y-317555D02*
X495519Y-316190D01*
G01X499312Y-310100D02*
X500409Y-316400D01*
X501662Y-310100D01*
X502915Y-316400D01*
X504012Y-310100D01*
G01X509529Y-316400D02*
X506395D01*
Y-310100D01*
X509529D01*
G01X508275Y-313145D02*
X506395D01*
G01X512460Y-316400D02*
Y-310100D01*
X516064Y-316400D01*
Y-310100D01*
G01X525217Y-316400D02*
Y-310100D01*
G01X528507D02*
Y-316400D01*
G01Y-313250D02*
X525217D01*
G01X530812Y-310100D02*
X531909Y-316400D01*
X533162Y-310100D01*
X534415Y-316400D01*
X535512Y-310100D01*
G01X537504Y-316400D02*
X539462Y-310100D01*
X541420Y-316400D01*
G01X540715Y-314195D02*
X538209D01*
G01X550574Y-311150D02*
X551044Y-310520D01*
X551592Y-310205D01*
X552219Y-310100D01*
X553002Y-310310D01*
X553550Y-310835D01*
X553707Y-311465D01*
X553629Y-312095D01*
X553315Y-312620D01*
X551749Y-313670D01*
X551044Y-314405D01*
X550574Y-315455D01*
X550417Y-316400D01*
X553707D01*
G01X556560D02*
Y-310100D01*
X560164Y-316400D01*
Y-310100D01*
G01X562939Y-316400D02*
Y-310100D01*
X564505D01*
X565132Y-310415D01*
X565602Y-310835D01*
X565994Y-311465D01*
X566307Y-312200D01*
X566385Y-313250D01*
X566307Y-314300D01*
X565994Y-315035D01*
X565602Y-315665D01*
X565132Y-316085D01*
X564505Y-316400D01*
X562939D01*
G01X575695D02*
Y-310100D01*
X577654D01*
X578280Y-310415D01*
X578672Y-310835D01*
X578829Y-311675D01*
X578672Y-312515D01*
X578202Y-313040D01*
X577654Y-313355D01*
X575695D01*
G01X577654D02*
X578829Y-316400D01*
G01X581839D02*
Y-310100D01*
X583405D01*
X584032Y-310415D01*
X584502Y-310835D01*
X584894Y-311465D01*
X585207Y-312200D01*
X585285Y-313250D01*
X585207Y-314300D01*
X584894Y-315035D01*
X584502Y-315665D01*
X584032Y-316085D01*
X583405Y-316400D01*
X581839D01*
G01X589862Y-316610D02*
X589705Y-316505D01*
Y-316295D01*
X589862Y-316190D01*
X590019Y-316295D01*
Y-316505D01*
X589862Y-316610D01*
G01X479862Y-303700D02*
X477342Y-303283D01*
X475137Y-301617D01*
X473247Y-299117D01*
X471987Y-296200D01*
X471357Y-292867D01*
Y-289533D01*
X471987Y-286200D01*
X473247Y-283283D01*
X475137Y-280784D01*
X477342Y-279117D01*
X479862Y-278700D01*
X482382Y-279117D01*
X484587Y-280784D01*
X486477Y-283283D01*
X487737Y-286200D01*
X488367Y-289533D01*
Y-292867D01*
X487737Y-296200D01*
X486477Y-299117D01*
X484587Y-301617D01*
X482382Y-303283D01*
X479862Y-303700D01*
G01X482382Y-297033D02*
X486162Y-303700D01*
G01X499707Y-287034D02*
Y-298700D01*
X500967Y-301617D01*
X502857Y-303283D01*
X505062Y-303700D01*
X507267Y-303283D01*
X509157Y-301617D01*
X510417Y-298700D01*
G01Y-303700D02*
Y-287034D01*
G01X535932Y-303700D02*
Y-287034D01*
G01Y-289950D02*
X534672Y-288284D01*
X532782Y-287450D01*
X530577Y-287034D01*
X528372Y-287867D01*
X526482Y-289533D01*
X525222Y-292034D01*
X524592Y-295367D01*
X525222Y-298700D01*
X526482Y-301201D01*
X528372Y-302867D01*
X530577Y-303700D01*
X532782Y-303283D01*
X534672Y-302034D01*
X535932Y-300367D01*
G01X550107Y-303700D02*
Y-287034D01*
G01Y-291200D02*
X551367Y-289117D01*
X553257Y-287450D01*
X555777Y-287034D01*
X557982Y-287450D01*
X559872Y-289117D01*
X560817Y-292034D01*
Y-303700D01*
G01X580662Y-278700D02*
Y-303700D01*
G01X576252Y-287034D02*
X585072D01*
G01X611532Y-303700D02*
Y-287034D01*
G01Y-289950D02*
X610272Y-288284D01*
X608382Y-287450D01*
X606177Y-287034D01*
X603972Y-287867D01*
X602082Y-289533D01*
X600822Y-292034D01*
X600192Y-295367D01*
X600822Y-298700D01*
X602082Y-301201D01*
X603972Y-302867D01*
X606177Y-303700D01*
X608382Y-303283D01*
X610272Y-302034D01*
X611532Y-300367D01*
G01X651212Y-283400D02*
Y-291400D01*
X655212D01*
G01X663012D02*
Y-286067D01*
G01Y-287000D02*
X662612Y-286467D01*
X662012Y-286200D01*
X661312Y-286067D01*
X660612Y-286333D01*
X660012Y-286867D01*
X659612Y-287667D01*
X659412Y-288733D01*
X659612Y-289800D01*
X660012Y-290600D01*
X660612Y-291133D01*
X661312Y-291400D01*
X662012Y-291267D01*
X662612Y-290867D01*
X663012Y-290334D01*
G01X667112Y-293800D02*
X667712Y-294067D01*
X668512Y-293800D01*
X669012Y-293267D01*
X669412Y-292600D01*
X670012Y-290467D01*
X671312Y-286067D01*
G01X668112D02*
X670012Y-290467D01*
G01X675712Y-287800D02*
X678912D01*
X678612Y-286867D01*
X678112Y-286333D01*
X677412Y-286067D01*
X676712Y-286200D01*
X676112Y-286600D01*
X675712Y-287533D01*
X675512Y-288334D01*
Y-289133D01*
X675712Y-289933D01*
X676212Y-290733D01*
X676812Y-291267D01*
X677512Y-291400D01*
X678212Y-291133D01*
X678912Y-290334D01*
G01X683812Y-291400D02*
Y-286067D01*
G01Y-287133D02*
X684312Y-286600D01*
X684812Y-286200D01*
X685512Y-286067D01*
X686012Y-286200D01*
X686612Y-286600D01*
G01X673512Y-333400D02*
X675912D01*
G01X674712D02*
Y-341400D01*
G01X673512D02*
X675912D01*
G01X681312D02*
Y-336067D01*
G01Y-337133D02*
X681812Y-336600D01*
X682312Y-336200D01*
X683012Y-336067D01*
X683512Y-336200D01*
X684112Y-336600D01*
G01X689212Y-337800D02*
X692412D01*
X692112Y-336867D01*
X691612Y-336333D01*
X690912Y-336067D01*
X690212Y-336200D01*
X689612Y-336600D01*
X689212Y-337533D01*
X689012Y-338334D01*
Y-339133D01*
X689212Y-339933D01*
X689712Y-340733D01*
X690312Y-341267D01*
X691012Y-341400D01*
X691712Y-341133D01*
X692412Y-340334D01*
G01X697012Y-341400D02*
Y-336067D01*
G01Y-337400D02*
X697412Y-336733D01*
X698012Y-336200D01*
X698812Y-336067D01*
X699512Y-336200D01*
X700112Y-336733D01*
X700412Y-337667D01*
Y-341400D01*
G01X705212Y-337800D02*
X708412D01*
X708112Y-336867D01*
X707612Y-336333D01*
X706912Y-336067D01*
X706212Y-336200D01*
X705612Y-336600D01*
X705212Y-337533D01*
X705012Y-338334D01*
Y-339133D01*
X705212Y-339933D01*
X705712Y-340733D01*
X706312Y-341267D01*
X707012Y-341400D01*
X707712Y-341133D01*
X708412Y-340334D01*
G01X682212Y-308400D02*
X684712Y-316400D01*
X687212Y-308400D01*
G01X694912Y-309067D02*
X694312Y-308667D01*
X693612Y-308400D01*
X692812D01*
X691912Y-308800D01*
X691212Y-309467D01*
X690712Y-310267D01*
X690312Y-311600D01*
X690212Y-312800D01*
X690412Y-314000D01*
X690712Y-314800D01*
X691312Y-315600D01*
X692012Y-316133D01*
X692712Y-316400D01*
X693412D01*
X694112Y-316133D01*
X694712Y-315733D01*
X695212Y-315200D01*
G01X702912Y-309067D02*
X702312Y-308667D01*
X701612Y-308400D01*
X700812D01*
X699912Y-308800D01*
X699212Y-309467D01*
X698712Y-310267D01*
X698312Y-311600D01*
X698212Y-312800D01*
X698412Y-314000D01*
X698712Y-314800D01*
X699312Y-315600D01*
X700012Y-316133D01*
X700712Y-316400D01*
X701412D01*
X702112Y-316133D01*
X702712Y-315733D01*
X703212Y-315200D01*
G01X708712Y-316400D02*
Y-308400D01*
X707512Y-310000D01*
G01Y-316400D02*
X709912D01*
G01X702512Y-290200D02*
X703112Y-290867D01*
X703812Y-291267D01*
X704712Y-291400D01*
X705612Y-291133D01*
X706312Y-290600D01*
X706812Y-289667D01*
X706912Y-288600D01*
X706712Y-287533D01*
X706212Y-286867D01*
X705512Y-286333D01*
X704812Y-286200D01*
X704112Y-286333D01*
X703212Y-286867D01*
X703512Y-283400D01*
X706212D01*
G01X777812Y-334733D02*
X778412Y-333933D01*
X779112Y-333533D01*
X779912Y-333400D01*
X780912Y-333667D01*
X781612Y-334333D01*
X781812Y-335133D01*
X781712Y-335934D01*
X781312Y-336600D01*
X779312Y-337933D01*
X778412Y-338867D01*
X777812Y-340200D01*
X777612Y-341400D01*
X781812D01*
G01X787712Y-333400D02*
X786912Y-333667D01*
X786312Y-334333D01*
X785912Y-335133D01*
X785612Y-336200D01*
X785512Y-337400D01*
X785612Y-338600D01*
X785912Y-339667D01*
X786312Y-340467D01*
X786912Y-341133D01*
X787712Y-341400D01*
X788512Y-341133D01*
X789112Y-340467D01*
X789512Y-339667D01*
X789812Y-338600D01*
X789912Y-337400D01*
X789812Y-336200D01*
X789512Y-335133D01*
X789112Y-334333D01*
X788512Y-333667D01*
X787712Y-333400D01*
G01X795712Y-341400D02*
Y-333400D01*
X794512Y-335000D01*
G01Y-341400D02*
X796912D01*
G01X801812Y-334733D02*
X802412Y-333933D01*
X803112Y-333533D01*
X803912Y-333400D01*
X804912Y-333667D01*
X805612Y-334333D01*
X805812Y-335133D01*
X805712Y-335934D01*
X805312Y-336600D01*
X803312Y-337933D01*
X802412Y-338867D01*
X801812Y-340200D01*
X801612Y-341400D01*
X805812D01*
G01X809912Y-341667D02*
X813512Y-333400D01*
G01X819712Y-341400D02*
Y-333400D01*
X818512Y-335000D01*
G01Y-341400D02*
X820912D01*
G01X827712Y-333400D02*
X826912Y-333667D01*
X826312Y-334333D01*
X825912Y-335133D01*
X825612Y-336200D01*
X825512Y-337400D01*
X825612Y-338600D01*
X825912Y-339667D01*
X826312Y-340467D01*
X826912Y-341133D01*
X827712Y-341400D01*
X828512Y-341133D01*
X829112Y-340467D01*
X829512Y-339667D01*
X829812Y-338600D01*
X829912Y-337400D01*
X829812Y-336200D01*
X829512Y-335133D01*
X829112Y-334333D01*
X828512Y-333667D01*
X827712Y-333400D01*
G01X833912Y-341667D02*
X837512Y-333400D01*
G01X841512Y-339800D02*
X842112Y-340733D01*
X842912Y-341267D01*
X843812Y-341400D01*
X844612Y-341267D01*
X845412Y-340600D01*
X845912Y-339800D01*
X846012Y-339000D01*
X845812Y-338067D01*
X845112Y-337400D01*
X844412Y-337133D01*
X843512D01*
G01X844412D02*
X845012Y-336733D01*
X845512Y-336067D01*
X845712Y-335267D01*
X845512Y-334467D01*
X845012Y-333800D01*
X844112Y-333400D01*
X843212Y-333533D01*
X842312Y-334067D01*
G01X851712Y-341400D02*
Y-333400D01*
X850512Y-335000D01*
G01Y-341400D02*
X852912D01*
G01X777512Y-316400D02*
Y-308400D01*
X779512D01*
X780312Y-308800D01*
X780912Y-309333D01*
X781412Y-310133D01*
X781812Y-311067D01*
X781912Y-312400D01*
X781812Y-313733D01*
X781412Y-314667D01*
X780912Y-315467D01*
X780312Y-316000D01*
X779512Y-316400D01*
X777512D01*
G01X785212D02*
X787712Y-308400D01*
X790212Y-316400D01*
G01X789312Y-313600D02*
X786112D01*
G01X795712Y-308400D02*
X794912Y-308667D01*
X794312Y-309333D01*
X793912Y-310133D01*
X793612Y-311200D01*
X793512Y-312400D01*
X793612Y-313600D01*
X793912Y-314667D01*
X794312Y-315467D01*
X794912Y-316133D01*
X795712Y-316400D01*
X796512Y-316133D01*
X797112Y-315467D01*
X797512Y-314667D01*
X797812Y-313600D01*
X797912Y-312400D01*
X797812Y-311200D01*
X797512Y-310133D01*
X797112Y-309333D01*
X796512Y-308667D01*
X795712Y-308400D01*
G01X803712D02*
Y-316400D01*
G01X801412Y-308400D02*
X806012D01*
G01X809812Y-313067D02*
X810512Y-312133D01*
X811112Y-311600D01*
X811912Y-311333D01*
X812612Y-311600D01*
X813112Y-312133D01*
X813512Y-312933D01*
X813612Y-313867D01*
X813512Y-314667D01*
X813112Y-315467D01*
X812512Y-316133D01*
X811812Y-316400D01*
X811012Y-316133D01*
X810312Y-315334D01*
X809912Y-314133D01*
X809812Y-312800D01*
X810012Y-311067D01*
X810312Y-310133D01*
X810812Y-309200D01*
X811512Y-308533D01*
X812212Y-308400D01*
X812912Y-308667D01*
X813412Y-309333D01*
G01X817112Y-316400D02*
Y-308400D01*
X819712Y-315067D01*
X822312Y-308400D01*
Y-316400D01*
G01X827712Y-308400D02*
Y-316400D01*
G01X825412Y-308400D02*
X830012D01*
G01X833612Y-316400D02*
Y-308400D01*
G01X837812D02*
Y-316400D01*
G01Y-312400D02*
X833612D01*
G01X843712Y-316400D02*
X844412Y-316267D01*
X845212Y-315867D01*
X845712Y-315200D01*
X845912Y-314267D01*
X845712Y-313334D01*
X845112Y-312533D01*
X844212Y-312133D01*
X843212D01*
X842612Y-311867D01*
X842112Y-311200D01*
X841912Y-310267D01*
X842212Y-309333D01*
X842912Y-308667D01*
X843712Y-308400D01*
X844512Y-308667D01*
X845212Y-309333D01*
X845512Y-310267D01*
X845312Y-311200D01*
X844812Y-311867D01*
X844212Y-312133D01*
X843212D01*
X842312Y-312533D01*
X841712Y-313334D01*
X841512Y-314267D01*
X841712Y-315200D01*
X842212Y-315867D01*
X843012Y-316267D01*
X843712Y-316400D01*
G01X853912Y-309067D02*
X853312Y-308667D01*
X852612Y-308400D01*
X851812D01*
X850912Y-308800D01*
X850212Y-309467D01*
X849712Y-310267D01*
X849312Y-311600D01*
X849212Y-312800D01*
X849412Y-314000D01*
X849712Y-314800D01*
X850312Y-315600D01*
X851012Y-316133D01*
X851712Y-316400D01*
X852412D01*
X853112Y-316133D01*
X853712Y-315733D01*
X854212Y-315200D01*
G01X859712Y-308400D02*
X858912Y-308667D01*
X858312Y-309333D01*
X857912Y-310133D01*
X857612Y-311200D01*
X857512Y-312400D01*
X857612Y-313600D01*
X857912Y-314667D01*
X858312Y-315467D01*
X858912Y-316133D01*
X859712Y-316400D01*
X860512Y-316133D01*
X861112Y-315467D01*
X861512Y-314667D01*
X861812Y-313600D01*
X861912Y-312400D01*
X861812Y-311200D01*
X861512Y-310133D01*
X861112Y-309333D01*
X860512Y-308667D01*
X859712Y-308400D01*
G01X799712Y-283400D02*
Y-291400D01*
G01X797412Y-283400D02*
X802012D01*
G01X805812Y-288067D02*
X806512Y-287133D01*
X807112Y-286600D01*
X807912Y-286333D01*
X808612Y-286600D01*
X809112Y-287133D01*
X809512Y-287933D01*
X809612Y-288867D01*
X809512Y-289667D01*
X809112Y-290467D01*
X808512Y-291133D01*
X807812Y-291400D01*
X807012Y-291133D01*
X806312Y-290334D01*
X805912Y-289133D01*
X805812Y-287800D01*
X806012Y-286067D01*
X806312Y-285133D01*
X806812Y-284200D01*
X807512Y-283533D01*
X808212Y-283400D01*
X808912Y-283667D01*
X809412Y-284333D01*
G01X813112Y-291400D02*
Y-283400D01*
X815712Y-290067D01*
X818312Y-283400D01*
Y-291400D01*
G01X820712Y-294067D02*
X826712D01*
G01X831712Y-283400D02*
Y-291400D01*
G01X829412Y-283400D02*
X834012D01*
G01X838312Y-291400D02*
Y-286067D01*
G01Y-287133D02*
X838812Y-286600D01*
X839312Y-286200D01*
X840012Y-286067D01*
X840512Y-286200D01*
X841112Y-286600D01*
G01X849512Y-291400D02*
Y-286067D01*
G01Y-287000D02*
X849112Y-286467D01*
X848512Y-286200D01*
X847812Y-286067D01*
X847112Y-286333D01*
X846512Y-286867D01*
X846112Y-287667D01*
X845912Y-288733D01*
X846112Y-289800D01*
X846512Y-290600D01*
X847112Y-291133D01*
X847812Y-291400D01*
X848512Y-291267D01*
X849112Y-290867D01*
X849512Y-290334D01*
G01X853612Y-293800D02*
X854212Y-294067D01*
X855012Y-293800D01*
X855512Y-293267D01*
X855912Y-292600D01*
X856512Y-290467D01*
X857812Y-286067D01*
G01X854612D02*
X856512Y-290467D01*
G01X860712Y-294067D02*
X866712D01*
G01X872512Y-287133D02*
X872912Y-286733D01*
X873212Y-286067D01*
X873412Y-285133D01*
X873212Y-284333D01*
X872812Y-283800D01*
X872112Y-283400D01*
X869412D01*
Y-291400D01*
X872712D01*
X873412Y-290867D01*
X873812Y-290067D01*
X874012Y-289133D01*
X873812Y-288200D01*
X873212Y-287400D01*
X872512Y-287133D01*
X869412D01*
G01X877712Y-291400D02*
Y-283400D01*
X880112D01*
X880912Y-283800D01*
X881512Y-284733D01*
X881712Y-285800D01*
X881512Y-286867D01*
X881012Y-287667D01*
X880112Y-288067D01*
X877712D01*
G01X896912Y-334067D02*
X896312Y-333667D01*
X895612Y-333400D01*
X894812D01*
X893912Y-333800D01*
X893212Y-334467D01*
X892712Y-335267D01*
X892312Y-336600D01*
X892212Y-337800D01*
X892412Y-339000D01*
X892712Y-339800D01*
X893312Y-340600D01*
X894012Y-341133D01*
X894712Y-341400D01*
X895412D01*
X896112Y-341133D01*
X896712Y-340733D01*
X897212Y-340200D01*
G01X922212Y-341400D02*
Y-333400D01*
X921012Y-335000D01*
G01Y-341400D02*
X923412D01*
G01X928312Y-338067D02*
X929012Y-337133D01*
X929612Y-336600D01*
X930412Y-336333D01*
X931112Y-336600D01*
X931612Y-337133D01*
X932012Y-337933D01*
X932112Y-338867D01*
X932012Y-339667D01*
X931612Y-340467D01*
X931012Y-341133D01*
X930312Y-341400D01*
X929512Y-341133D01*
X928812Y-340334D01*
X928412Y-339133D01*
X928312Y-337800D01*
X928512Y-336067D01*
X928812Y-335133D01*
X929312Y-334200D01*
X930012Y-333533D01*
X930712Y-333400D01*
X931412Y-333667D01*
X931912Y-334333D01*
M02*
